FILE_TYPE = MACRO_DRAWING;
SET COLOR_WIRE YELLOW;
SET COLOR_PROP ORANGE;
SET COLOR_DOT WHITE;
SET COLOR_ARC YELLOW;
SET COLOR_BODY GREEN;
SET COLOR_NOTE PURPLE;
SET PROP_DISPLAY VALUE;
SET PAGE_NUMBER P433;
FORCEADD Q_RES..1
(-7850 3750);
FORCEPROP 1 LAST LOCATION R1087
J 0
(-8125 3750);
DISPLAY 0.787234 (-8125 3750);
FORCEPROP 2 LAST SEC 1
J 0
(-7900 3950);
DISPLAY 0.680851 (-7900 3950);
PAINT MONO (-7900 3950);
DISPLAY INVISIBLE (-7900 3950);
FORCEPROP 1 LASTPIN (-7950 3750) $PN 1
J 0
(-7938 3762);
DISPLAY 0.787234 (-7938 3762);
PAINT MONO (-7938 3762);
FORCEPROP 1 LASTPIN (-7750 3750) $PN 2
J 0
(-7788 3762);
DISPLAY 0.787234 (-7788 3762);
PAINT MONO (-7788 3762);
FORCEPROP 1 LAST WATTAGE 1/16W
J 2
(-7850 3650);
DISPLAY 0.638298 (-7850 3650);
FORCEPROP 1 LAST PACK_TYPE 0402LF
J 0
(-8000 3700);
DISPLAY 0.638298 (-8000 3700);
FORCEPROP 1 LAST VALUE 0
J 2
(-7700 3775);
DISPLAY 0.638298 (-7700 3775);
FORCEPROP 1 LAST MATERIAL EMPTY
J 0
(-7825 3650);
DISPLAY 0.638298 (-7825 3650);
FORCEPROP 1 LAST TOLERANCE 5%
J 0
(-7800 3700);
DISPLAY 0.638298 (-7800 3700);
FORCEPROP 2 LAST SEC_TYPE 0402LF
J 0
(-7900 3950);
DISPLAY 0.680851 (-7900 3950);
DISPLAY INVISIBLE (-7900 3950);
FORCEPROP 2 LAST CDS_LIB pure_quanta
J 0
(-7850 3750);
DISPLAY INVISIBLE (-7850 3750);
FORCEPROP 1 LAST PATH I1
J 0
(-7900 3900);
DISPLAY 0.978723 (-7900 3900);
PAINT WHITE (-7900 3900);
DISPLAY INVISIBLE (-7900 3900);
FORCEPROP 1 LAST PART_NUMBER CS00002JB13
J 0
(-7900 3850);
DISPLAY 0.978723 (-7900 3850);
DISPLAY INVISIBLE (-7900 3850);
FORCEADD Q_INDUCTOR..1
(-7925 4650);
FORCEPROP 1 LAST LOCATION L22
J 0
(-8050 4810);
DISPLAY 0.723404 (-8050 4810);
PAINT GREEN (-8050 4810);
FORCEPROP 0 LAST $SEC 1
J 0
(-8050 4900);
DISPLAY 0.680851 (-8050 4900);
PAINT MONO (-8050 4900);
DISPLAY INVISIBLE (-8050 4900);
FORCEPROP 0 LAST CDS_SEC 1
J 0
(-8050 4900);
DISPLAY 0.680851 (-8050 4900);
DISPLAY INVISIBLE (-8050 4900);
FORCEPROP 0 LASTPIN (-8025 4625) $PN 1
J 2
(-8035 4635);
DISPLAY 0.680851 (-8035 4635);
PAINT MONO (-8035 4635);
FORCEPROP 0 LASTPIN (-7825 4625) $PN 2
J 0
(-7815 4635);
DISPLAY 0.680851 (-7815 4635);
PAINT MONO (-7815 4635);
FORCEPROP 2 LAST PACK_TYPE SMLF
J 0
(-8050 4850);
DISPLAY 0.680851 (-8050 4850);
FORCEPROP 2 LAST VALUE BLM21SN300SN1D/5A
J 0
(-8175 4550);
DISPLAY 0.680851 (-8175 4550);
FORCEPROP 1 LAST MATERIAL IND
J 0
(-8050 4705);
DISPLAY 0.723404 (-8050 4705);
PAINT GREEN (-8050 4705);
FORCEPROP 1 LAST NEEDS_NO_SIZE TRUE
J 0
(-7925 4650);
DISPLAY 0.468085 (-7925 4650);
PAINT GREEN (-7925 4650);
DISPLAY INVISIBLE (-7925 4650);
FORCEPROP 2 LAST CDS_LIB pure_quanta
J 0
(-7925 4650);
DISPLAY INVISIBLE (-7925 4650);
FORCEPROP 1 LAST PATH I10
J 0
(-7850 4705);
DISPLAY 0.723404 (-7850 4705);
PAINT GREEN (-7850 4705);
DISPLAY INVISIBLE (-7850 4705);
FORCEPROP 1 LAST PART_NUMBER CX300SN1000
J 0
(-8050 4760);
DISPLAY 0.723404 (-8050 4760);
PAINT GREEN (-8050 4760);
DISPLAY INVISIBLE (-8050 4760);
FORCEADD P1V0..1
(-8300 5475);
FORCEPROP 3 LASTPIN (-8300 5425) SIG_NAME P1V8_CPU0_RT_1D\g
J 0
(-8290 5435);
DISPLAY 0.659574 (-8290 5435);
PAINT MONO (-8290 5435);
DISPLAY INVISIBLE (-8290 5435);
FORCEPROP 1 LAST HDL_POWER P1V8_CPU0_RT_1D
J 1
(-8300 5525);
DISPLAY 0.489362 (-8300 5525);
PAINT SKYBLUE (-8300 5525);
FORCEPROP 2 LAST CDS_LIB pure_quanta_power
J 0
(-8300 5475);
DISPLAY INVISIBLE (-8300 5475);
FORCEPROP 1 LAST PATH I11
J 0
(-8250 5500);
DISPLAY 0.872340 (-8250 5500);
PAINT AQUA (-8250 5500);
DISPLAY INVISIBLE (-8250 5500);
FORCEADD Q_CAP..1
(-7350 4375);
FORCEPROP 1 LAST LOCATION C991
J 0
(-7300 4475);
DISPLAY 0.638298 (-7300 4475);
PAINT WHITE (-7300 4475);
FORCEPROP 0 LAST $SEC 1
J 0
(-7300 4500);
DISPLAY 0.680851 (-7300 4500);
PAINT MONO (-7300 4500);
DISPLAY INVISIBLE (-7300 4500);
FORCEPROP 0 LAST CDS_SEC 1
J 0
(-7300 4500);
DISPLAY 0.680851 (-7300 4500);
DISPLAY INVISIBLE (-7300 4500);
FORCEPROP 1 LASTPIN (-7350 4475) $PN 1
J 0
(-7340 4455);
DISPLAY 0.787234 (-7340 4455);
PAINT MONO (-7340 4455);
FORCEPROP 1 LASTPIN (-7350 4275) $PN 2
J 0
(-7340 4255);
DISPLAY 0.787234 (-7340 4255);
PAINT MONO (-7340 4255);
FORCEPROP 1 LAST TOLERANCE 20%
J 0
(-7300 4325);
DISPLAY 0.510638 (-7300 4325);
FORCEPROP 1 LAST VALUE 100UF
J 0
(-7300 4425);
DISPLAY 0.510638 (-7300 4425);
FORCEPROP 1 LAST PACK_TYPE C0805
J 0
(-7300 4225);
DISPLAY 0.510638 (-7300 4225);
FORCEPROP 1 LAST VOLTAGE 4V
J 0
(-7300 4375);
DISPLAY 0.510638 (-7300 4375);
FORCEPROP 1 LAST MATERIAL X6S
J 0
(-7300 4275);
DISPLAY 0.510638 (-7300 4275);
FORCEPROP 2 LAST CDS_LIB pure_quanta
J 0
(-7350 4375);
DISPLAY INVISIBLE (-7350 4375);
FORCEPROP 1 LAST PATH I12
J 0
(-7300 4525);
DISPLAY 0.978723 (-7300 4525);
PAINT WHITE (-7300 4525);
DISPLAY INVISIBLE (-7300 4525);
FORCEPROP 1 LAST PART_NUMBER CH710KMEA01
J 0
(-7300 4225);
DISPLAY 0.404255 (-7300 4225);
DISPLAY INVISIBLE (-7300 4225);
FORCEADD Q_CAP..1
(-7125 4375);
FORCEPROP 1 LAST LOCATION C993
J 0
(-7075 4475);
DISPLAY 0.638298 (-7075 4475);
PAINT WHITE (-7075 4475);
FORCEPROP 0 LAST $SEC 1
J 0
(-7075 4500);
DISPLAY 0.680851 (-7075 4500);
PAINT MONO (-7075 4500);
DISPLAY INVISIBLE (-7075 4500);
FORCEPROP 0 LAST CDS_SEC 1
J 0
(-7075 4500);
DISPLAY 0.680851 (-7075 4500);
DISPLAY INVISIBLE (-7075 4500);
FORCEPROP 1 LASTPIN (-7125 4475) $PN 1
J 0
(-7115 4455);
DISPLAY 0.787234 (-7115 4455);
PAINT MONO (-7115 4455);
FORCEPROP 1 LASTPIN (-7125 4275) $PN 2
J 0
(-7115 4255);
DISPLAY 0.787234 (-7115 4255);
PAINT MONO (-7115 4255);
FORCEPROP 1 LAST PACK_TYPE C0402
J 0
(-7075 4225);
DISPLAY 0.510638 (-7075 4225);
FORCEPROP 1 LAST TOLERANCE 20%
J 0
(-7075 4325);
DISPLAY 0.510638 (-7075 4325);
FORCEPROP 1 LAST MATERIAL X6S
J 0
(-7075 4275);
DISPLAY 0.510638 (-7075 4275);
FORCEPROP 1 LAST VALUE 22UF
J 0
(-7075 4425);
DISPLAY 0.510638 (-7075 4425);
FORCEPROP 1 LAST VOLTAGE 4V
J 0
(-7075 4375);
DISPLAY 0.510638 (-7075 4375);
FORCEPROP 2 LAST CDS_LIB pure_quanta
J 0
(-7125 4375);
DISPLAY INVISIBLE (-7125 4375);
FORCEPROP 1 LAST PATH I13
J 0
(-7075 4525);
DISPLAY 0.978723 (-7075 4525);
PAINT WHITE (-7075 4525);
DISPLAY INVISIBLE (-7075 4525);
FORCEPROP 1 LAST PART_NUMBER CH622KMEB02
J 0
(-7075 4225);
DISPLAY 0.978723 (-7075 4225);
DISPLAY INVISIBLE (-7075 4225);
FORCEADD P1V0..1
(-7450 4850);
FORCEPROP 3 LASTPIN (-7450 4800) SIG_NAME P1V8_CPU0_RT3_1A\g
J 0
(-7440 4810);
DISPLAY 0.659574 (-7440 4810);
PAINT MONO (-7440 4810);
DISPLAY INVISIBLE (-7440 4810);
FORCEPROP 1 LAST HDL_POWER P1V8_CPU0_RT3_1A
J 1
(-7450 4900);
DISPLAY 0.489362 (-7450 4900);
PAINT SKYBLUE (-7450 4900);
FORCEPROP 2 LAST CDS_LIB pure_quanta_power
J 0
(-7450 4850);
DISPLAY INVISIBLE (-7450 4850);
FORCEPROP 1 LAST PATH I14
J 0
(-7400 4875);
DISPLAY 0.872340 (-7400 4875);
PAINT AQUA (-7400 4875);
DISPLAY INVISIBLE (-7400 4875);
FORCEADD Q_CAP..1
(-6925 4375);
FORCEPROP 1 LAST LOCATION C995
J 0
(-6875 4475);
DISPLAY 0.808511 (-6875 4475);
PAINT WHITE (-6875 4475);
FORCEPROP 0 LAST $SEC 1
J 0
(-6875 4525);
DISPLAY 0.680851 (-6875 4525);
PAINT MONO (-6875 4525);
DISPLAY INVISIBLE (-6875 4525);
FORCEPROP 0 LAST CDS_SEC 1
J 0
(-6875 4525);
DISPLAY 0.680851 (-6875 4525);
DISPLAY INVISIBLE (-6875 4525);
FORCEPROP 1 LASTPIN (-6925 4475) $PN 1
J 0
(-6915 4455);
DISPLAY 0.787234 (-6915 4455);
PAINT MONO (-6915 4455);
FORCEPROP 1 LASTPIN (-6925 4275) $PN 2
J 0
(-6915 4255);
DISPLAY 0.787234 (-6915 4255);
PAINT MONO (-6915 4255);
FORCEPROP 1 LAST PACK_TYPE C0402
J 0
(-6875 4225);
DISPLAY 0.510638 (-6875 4225);
FORCEPROP 1 LAST TOLERANCE 20%
J 0
(-6875 4325);
DISPLAY 0.510638 (-6875 4325);
FORCEPROP 1 LAST MATERIAL X6S
J 0
(-6875 4275);
DISPLAY 0.510638 (-6875 4275);
FORCEPROP 1 LAST VALUE 10UF
J 0
(-6875 4425);
DISPLAY 0.510638 (-6875 4425);
FORCEPROP 1 LAST VOLTAGE 6.3V
J 0
(-6875 4375);
DISPLAY 0.510638 (-6875 4375);
FORCEPROP 2 LAST CDS_LIB pure_quanta
J 0
(-6925 4375);
DISPLAY INVISIBLE (-6925 4375);
FORCEPROP 1 LAST PATH I15
J 0
(-6875 4525);
DISPLAY 0.978723 (-6875 4525);
PAINT WHITE (-6875 4525);
DISPLAY INVISIBLE (-6875 4525);
FORCEPROP 1 LAST PART_NUMBER CH6101MEB01
J 0
(-6875 4225);
DISPLAY 0.978723 (-6875 4225);
DISPLAY INVISIBLE (-6875 4225);
FORCEADD Q_CAP..1
(-6725 4375);
FORCEPROP 1 LAST LOCATION C996
J 0
(-6675 4475);
DISPLAY 0.638298 (-6675 4475);
PAINT WHITE (-6675 4475);
FORCEPROP 0 LAST $SEC 1
J 0
(-6675 4500);
DISPLAY 0.680851 (-6675 4500);
PAINT MONO (-6675 4500);
DISPLAY INVISIBLE (-6675 4500);
FORCEPROP 0 LAST CDS_SEC 1
J 0
(-6675 4500);
DISPLAY 0.680851 (-6675 4500);
DISPLAY INVISIBLE (-6675 4500);
FORCEPROP 1 LASTPIN (-6725 4475) $PN 1
J 0
(-6715 4455);
DISPLAY 0.787234 (-6715 4455);
PAINT MONO (-6715 4455);
FORCEPROP 1 LASTPIN (-6725 4275) $PN 2
J 0
(-6715 4255);
DISPLAY 0.787234 (-6715 4255);
PAINT MONO (-6715 4255);
FORCEPROP 1 LAST VOLTAGE 6.3V
J 0
(-6675 4375);
DISPLAY 0.510638 (-6675 4375);
FORCEPROP 1 LAST VALUE 4.7UF
J 0
(-6675 4425);
DISPLAY 0.510638 (-6675 4425);
FORCEPROP 1 LAST MATERIAL X6S
J 0
(-6675 4275);
DISPLAY 0.510638 (-6675 4275);
FORCEPROP 1 LAST PACK_TYPE 0402
J 0
(-6675 4225);
DISPLAY 0.510638 (-6675 4225);
FORCEPROP 1 LAST TOLERANCE 20%
J 0
(-6675 4325);
DISPLAY 0.510638 (-6675 4325);
FORCEPROP 2 LAST CDS_LIB pure_quanta
J 0
(-6725 4375);
DISPLAY INVISIBLE (-6725 4375);
FORCEPROP 1 LAST PATH I16
J 0
(-6675 4525);
DISPLAY 0.978723 (-6675 4525);
PAINT WHITE (-6675 4525);
DISPLAY INVISIBLE (-6675 4525);
FORCEPROP 1 LAST PART_NUMBER CH5471MEB01
J 0
(-6675 4225);
DISPLAY 0.978723 (-6675 4225);
DISPLAY INVISIBLE (-6675 4225);
FORCEADD Q_CAP..1
(-6500 4375);
FORCEPROP 1 LAST LOCATION C998
J 0
(-6450 4475);
DISPLAY 0.808511 (-6450 4475);
PAINT WHITE (-6450 4475);
FORCEPROP 0 LAST $SEC 1
J 0
(-6450 4525);
DISPLAY 0.680851 (-6450 4525);
PAINT MONO (-6450 4525);
DISPLAY INVISIBLE (-6450 4525);
FORCEPROP 0 LAST CDS_SEC 1
J 0
(-6450 4525);
DISPLAY 0.680851 (-6450 4525);
DISPLAY INVISIBLE (-6450 4525);
FORCEPROP 1 LASTPIN (-6500 4475) $PN 1
J 0
(-6490 4455);
DISPLAY 0.787234 (-6490 4455);
PAINT MONO (-6490 4455);
FORCEPROP 1 LASTPIN (-6500 4275) $PN 2
J 0
(-6490 4255);
DISPLAY 0.787234 (-6490 4255);
PAINT MONO (-6490 4255);
FORCEPROP 1 LAST PACK_TYPE 0201
J 0
(-6450 4225);
DISPLAY 0.510638 (-6450 4225);
FORCEPROP 1 LAST MATERIAL X6S
J 0
(-6450 4275);
DISPLAY 0.510638 (-6450 4275);
FORCEPROP 1 LAST VALUE 1UF
J 0
(-6450 4425);
DISPLAY 0.510638 (-6450 4425);
FORCEPROP 1 LAST VOLTAGE 4V
J 0
(-6450 4375);
DISPLAY 0.510638 (-6450 4375);
FORCEPROP 1 LAST TOLERANCE 20%
J 0
(-6450 4325);
DISPLAY 0.510638 (-6450 4325);
FORCEPROP 2 LAST CDS_LIB pure_quanta
J 0
(-6500 4375);
DISPLAY INVISIBLE (-6500 4375);
FORCEPROP 1 LAST PATH I17
J 0
(-6450 4525);
DISPLAY 0.978723 (-6450 4525);
PAINT WHITE (-6450 4525);
DISPLAY INVISIBLE (-6450 4525);
FORCEPROP 1 LAST PART_NUMBER CH-10KMEE00
J 0
(-6450 4225);
DISPLAY 0.510638 (-6450 4225);
DISPLAY INVISIBLE (-6450 4225);
FORCEADD UNIVERSAL_GND..1
(-6525 4900);
FORCEPROP 3 LASTPIN (-6525 4950) SIG_NAME GND\g
J 0
(-6515 4960);
DISPLAY 0.659574 (-6515 4960);
PAINT MONO (-6515 4960);
DISPLAY INVISIBLE (-6515 4960);
FORCEPROP 2 LAST CDS_LIB pure_quanta_power
J 0
(-6525 4900);
DISPLAY INVISIBLE (-6525 4900);
FORCEPROP 1 LAST HDL_POWER GND
J 1
(-6500 4825);
DISPLAY 0.872340 (-6500 4825);
PAINT GREEN (-6500 4825);
DISPLAY INVISIBLE (-6500 4825);
FORCEPROP 1 LAST PATH I18
J 0
(-6450 4900);
DISPLAY 0.872340 (-6450 4900);
PAINT AQUA (-6450 4900);
DISPLAY INVISIBLE (-6450 4900);
FORCEADD Q_CAP..1
(-7200 5200);
FORCEPROP 1 LAST LOCATION C990
J 0
(-7150 5300);
DISPLAY 0.638298 (-7150 5300);
PAINT WHITE (-7150 5300);
FORCEPROP 0 LAST $SEC 1
J 0
(-7150 5350);
DISPLAY 0.680851 (-7150 5350);
PAINT MONO (-7150 5350);
DISPLAY INVISIBLE (-7150 5350);
FORCEPROP 0 LAST CDS_SEC 1
J 0
(-7150 5350);
DISPLAY 0.680851 (-7150 5350);
DISPLAY INVISIBLE (-7150 5350);
FORCEPROP 1 LASTPIN (-7200 5300) $PN 1
J 0
(-7190 5280);
DISPLAY 0.787234 (-7190 5280);
PAINT MONO (-7190 5280);
FORCEPROP 1 LASTPIN (-7200 5100) $PN 2
J 0
(-7190 5080);
DISPLAY 0.787234 (-7190 5080);
PAINT MONO (-7190 5080);
FORCEPROP 1 LAST PACK_TYPE C0805
J 0
(-7150 5050);
DISPLAY 0.510638 (-7150 5050);
FORCEPROP 1 LAST MATERIAL X6S
J 0
(-7150 5100);
DISPLAY 0.510638 (-7150 5100);
FORCEPROP 1 LAST TOLERANCE 20%
J 0
(-7150 5150);
DISPLAY 0.510638 (-7150 5150);
FORCEPROP 1 LAST VALUE 100UF
J 0
(-7150 5250);
DISPLAY 0.510638 (-7150 5250);
FORCEPROP 1 LAST VOLTAGE 4V
J 0
(-7150 5200);
DISPLAY 0.510638 (-7150 5200);
FORCEPROP 2 LAST CDS_LIB pure_quanta
J 0
(-7200 5200);
DISPLAY INVISIBLE (-7200 5200);
FORCEPROP 1 LAST PATH I19
J 0
(-7150 5350);
DISPLAY 0.978723 (-7150 5350);
PAINT WHITE (-7150 5350);
DISPLAY INVISIBLE (-7150 5350);
FORCEPROP 1 LAST PART_NUMBER CH710KMEA01
J 0
(-7150 5050);
DISPLAY 0.404255 (-7150 5050);
DISPLAY INVISIBLE (-7150 5050);
FORCEADD Q_RES..1
(-7850 3950);
FORCEPROP 1 LAST LOCATION R1086
J 0
(-8125 3975);
DISPLAY 0.808511 (-8125 3975);
FORCEPROP 2 LAST SEC 1
J 0
(-7900 4150);
DISPLAY 0.680851 (-7900 4150);
PAINT MONO (-7900 4150);
DISPLAY INVISIBLE (-7900 4150);
FORCEPROP 1 LASTPIN (-7950 3950) $PN 1
J 0
(-7938 3962);
DISPLAY 0.787234 (-7938 3962);
PAINT MONO (-7938 3962);
FORCEPROP 1 LASTPIN (-7750 3950) $PN 2
J 0
(-7788 3962);
DISPLAY 0.787234 (-7788 3962);
PAINT MONO (-7788 3962);
FORCEPROP 1 LAST MATERIAL EMPTY
J 0
(-7825 3850);
DISPLAY 0.638298 (-7825 3850);
FORCEPROP 1 LAST WATTAGE 1/16W
J 2
(-7850 3850);
DISPLAY 0.638298 (-7850 3850);
FORCEPROP 1 LAST PACK_TYPE 0402LF
J 0
(-8000 3900);
DISPLAY 0.638298 (-8000 3900);
FORCEPROP 1 LAST TOLERANCE 5%
J 0
(-7800 3900);
DISPLAY 0.638298 (-7800 3900);
FORCEPROP 1 LAST VALUE 0
J 2
(-7700 3975);
DISPLAY 0.638298 (-7700 3975);
FORCEPROP 2 LAST CDS_LIB pure_quanta
J 0
(-7850 3950);
DISPLAY INVISIBLE (-7850 3950);
FORCEPROP 2 LAST SEC_TYPE 0402LF
J 0
(-7900 4150);
DISPLAY 0.680851 (-7900 4150);
DISPLAY INVISIBLE (-7900 4150);
FORCEPROP 1 LAST PATH I2
J 0
(-7900 4100);
DISPLAY 0.978723 (-7900 4100);
PAINT WHITE (-7900 4100);
DISPLAY INVISIBLE (-7900 4100);
FORCEPROP 1 LAST PART_NUMBER CS00002JB13
J 0
(-7900 4050);
DISPLAY 0.978723 (-7900 4050);
DISPLAY INVISIBLE (-7900 4050);
FORCEADD Q_CAP..1
(-6950 5200);
FORCEPROP 1 LAST LOCATION C992
J 0
(-6900 5300);
DISPLAY 0.510638 (-6900 5300);
PAINT WHITE (-6900 5300);
FORCEPROP 0 LAST $SEC 1
J 0
(-6900 5325);
DISPLAY 0.680851 (-6900 5325);
PAINT MONO (-6900 5325);
DISPLAY INVISIBLE (-6900 5325);
FORCEPROP 0 LAST CDS_SEC 1
J 0
(-6900 5325);
DISPLAY 0.680851 (-6900 5325);
DISPLAY INVISIBLE (-6900 5325);
FORCEPROP 1 LASTPIN (-6950 5300) $PN 1
J 0
(-6940 5280);
DISPLAY 0.787234 (-6940 5280);
PAINT MONO (-6940 5280);
FORCEPROP 1 LASTPIN (-6950 5100) $PN 2
J 0
(-6940 5080);
DISPLAY 0.787234 (-6940 5080);
PAINT MONO (-6940 5080);
FORCEPROP 1 LAST PACK_TYPE C0402
J 0
(-6900 5050);
DISPLAY 0.510638 (-6900 5050);
FORCEPROP 1 LAST VALUE 22UF
J 0
(-6900 5250);
DISPLAY 0.510638 (-6900 5250);
FORCEPROP 1 LAST TOLERANCE 20%
J 0
(-6900 5150);
DISPLAY 0.510638 (-6900 5150);
FORCEPROP 1 LAST MATERIAL X6S
J 0
(-6900 5100);
DISPLAY 0.510638 (-6900 5100);
FORCEPROP 1 LAST VOLTAGE 4V
J 0
(-6900 5200);
DISPLAY 0.510638 (-6900 5200);
FORCEPROP 2 LAST CDS_LIB pure_quanta
J 0
(-6950 5200);
DISPLAY INVISIBLE (-6950 5200);
FORCEPROP 1 LAST PATH I20
J 0
(-6900 5350);
DISPLAY 0.978723 (-6900 5350);
PAINT WHITE (-6900 5350);
DISPLAY INVISIBLE (-6900 5350);
FORCEPROP 1 LAST PART_NUMBER CH622KMEB02
J 0
(-6900 5050);
DISPLAY 0.978723 (-6900 5050);
DISPLAY INVISIBLE (-6900 5050);
FORCEADD Q_CAP..1
(-6700 5175);
FORCEPROP 1 LAST LOCATION C994
J 0
(-6650 5275);
DISPLAY 0.638298 (-6650 5275);
PAINT WHITE (-6650 5275);
FORCEPROP 0 LAST $SEC 1
J 0
(-6650 5325);
DISPLAY 0.680851 (-6650 5325);
PAINT MONO (-6650 5325);
DISPLAY INVISIBLE (-6650 5325);
FORCEPROP 0 LAST CDS_SEC 1
J 0
(-6650 5325);
DISPLAY 0.680851 (-6650 5325);
DISPLAY INVISIBLE (-6650 5325);
FORCEPROP 1 LASTPIN (-6700 5275) $PN 1
J 0
(-6690 5255);
DISPLAY 0.787234 (-6690 5255);
PAINT MONO (-6690 5255);
FORCEPROP 1 LASTPIN (-6700 5075) $PN 2
J 0
(-6690 5055);
DISPLAY 0.787234 (-6690 5055);
PAINT MONO (-6690 5055);
FORCEPROP 1 LAST PACK_TYPE C0402
J 0
(-6650 5025);
DISPLAY 0.510638 (-6650 5025);
FORCEPROP 1 LAST VALUE 10UF
J 0
(-6650 5225);
DISPLAY 0.510638 (-6650 5225);
FORCEPROP 1 LAST VOLTAGE 6.3V
J 0
(-6650 5175);
DISPLAY 0.510638 (-6650 5175);
FORCEPROP 1 LAST TOLERANCE 20%
J 0
(-6650 5125);
DISPLAY 0.510638 (-6650 5125);
FORCEPROP 1 LAST MATERIAL X6S
J 0
(-6650 5075);
DISPLAY 0.510638 (-6650 5075);
FORCEPROP 2 LAST CDS_LIB pure_quanta
J 0
(-6700 5175);
DISPLAY INVISIBLE (-6700 5175);
FORCEPROP 1 LAST PATH I21
J 0
(-6650 5325);
DISPLAY 0.978723 (-6650 5325);
PAINT WHITE (-6650 5325);
DISPLAY INVISIBLE (-6650 5325);
FORCEPROP 1 LAST PART_NUMBER CH6101MEB01
J 0
(-6650 5025);
DISPLAY 0.978723 (-6650 5025);
DISPLAY INVISIBLE (-6650 5025);
FORCEADD Q_CAP..1
(-6450 5175);
FORCEPROP 1 LAST LOCATION C997
J 0
(-6400 5275);
DISPLAY 0.638298 (-6400 5275);
PAINT WHITE (-6400 5275);
FORCEPROP 0 LAST $SEC 1
J 0
(-6400 5325);
DISPLAY 0.680851 (-6400 5325);
PAINT MONO (-6400 5325);
DISPLAY INVISIBLE (-6400 5325);
FORCEPROP 0 LAST CDS_SEC 1
J 0
(-6400 5325);
DISPLAY 0.680851 (-6400 5325);
DISPLAY INVISIBLE (-6400 5325);
FORCEPROP 1 LASTPIN (-6450 5275) $PN 1
J 0
(-6440 5255);
DISPLAY 0.787234 (-6440 5255);
PAINT MONO (-6440 5255);
FORCEPROP 1 LASTPIN (-6450 5075) $PN 2
J 0
(-6440 5055);
DISPLAY 0.787234 (-6440 5055);
PAINT MONO (-6440 5055);
FORCEPROP 1 LAST VOLTAGE 6.3V
J 0
(-6400 5175);
DISPLAY 0.510638 (-6400 5175);
FORCEPROP 1 LAST VALUE 4.7UF
J 0
(-6400 5225);
DISPLAY 0.510638 (-6400 5225);
FORCEPROP 1 LAST PACK_TYPE 0402
J 0
(-6400 5025);
DISPLAY 0.510638 (-6400 5025);
FORCEPROP 1 LAST MATERIAL X6S
J 0
(-6400 5075);
DISPLAY 0.510638 (-6400 5075);
FORCEPROP 1 LAST TOLERANCE 20%
J 0
(-6400 5125);
DISPLAY 0.510638 (-6400 5125);
FORCEPROP 2 LAST CDS_LIB pure_quanta
J 0
(-6450 5175);
DISPLAY INVISIBLE (-6450 5175);
FORCEPROP 1 LAST PATH I22
J 0
(-6400 5325);
DISPLAY 0.978723 (-6400 5325);
PAINT WHITE (-6400 5325);
DISPLAY INVISIBLE (-6400 5325);
FORCEPROP 1 LAST PART_NUMBER CH5471MEB01
J 0
(-6400 5025);
DISPLAY 0.978723 (-6400 5025);
DISPLAY INVISIBLE (-6400 5025);
FORCEADD UNIVERSAL_GND..1
(-6300 4050);
FORCEPROP 3 LASTPIN (-6300 4100) SIG_NAME GND\g
J 0
(-6290 4110);
DISPLAY 0.659574 (-6290 4110);
PAINT MONO (-6290 4110);
DISPLAY INVISIBLE (-6290 4110);
FORCEPROP 2 LAST CDS_LIB pure_quanta_power
J 0
(-6300 4050);
DISPLAY INVISIBLE (-6300 4050);
FORCEPROP 1 LAST HDL_POWER GND
J 1
(-6275 3975);
DISPLAY 0.872340 (-6275 3975);
PAINT GREEN (-6275 3975);
DISPLAY INVISIBLE (-6275 3975);
FORCEPROP 1 LAST PATH I23
J 0
(-6225 4050);
DISPLAY 0.872340 (-6225 4050);
PAINT AQUA (-6225 4050);
DISPLAY INVISIBLE (-6225 4050);
FORCEADD Q_CAP..1
(-6300 4375);
FORCEPROP 1 LAST LOCATION C1000
J 0
(-6250 4475);
DISPLAY 0.808511 (-6250 4475);
PAINT WHITE (-6250 4475);
FORCEPROP 0 LAST $SEC 1
J 0
(-6250 4525);
DISPLAY 0.680851 (-6250 4525);
PAINT MONO (-6250 4525);
DISPLAY INVISIBLE (-6250 4525);
FORCEPROP 0 LAST CDS_SEC 1
J 0
(-6250 4525);
DISPLAY 0.680851 (-6250 4525);
DISPLAY INVISIBLE (-6250 4525);
FORCEPROP 1 LASTPIN (-6300 4475) $PN 1
J 0
(-6290 4455);
DISPLAY 0.787234 (-6290 4455);
PAINT MONO (-6290 4455);
FORCEPROP 1 LASTPIN (-6300 4275) $PN 2
J 0
(-6290 4255);
DISPLAY 0.787234 (-6290 4255);
PAINT MONO (-6290 4255);
FORCEPROP 1 LAST PACK_TYPE 0201
J 0
(-6250 4225);
DISPLAY 0.510638 (-6250 4225);
FORCEPROP 1 LAST TOLERANCE 20%
J 0
(-6250 4325);
DISPLAY 0.510638 (-6250 4325);
FORCEPROP 1 LAST MATERIAL X6S
J 0
(-6250 4275);
DISPLAY 0.510638 (-6250 4275);
FORCEPROP 1 LAST VOLTAGE 4V
J 0
(-6250 4375);
DISPLAY 0.510638 (-6250 4375);
FORCEPROP 1 LAST VALUE 1UF
J 0
(-6250 4425);
DISPLAY 0.510638 (-6250 4425);
FORCEPROP 2 LAST CDS_LIB pure_quanta
J 0
(-6300 4375);
DISPLAY INVISIBLE (-6300 4375);
FORCEPROP 1 LAST PATH I24
J 0
(-6250 4525);
DISPLAY 0.978723 (-6250 4525);
PAINT WHITE (-6250 4525);
DISPLAY INVISIBLE (-6250 4525);
FORCEPROP 1 LAST PART_NUMBER CH-10KMEE00
J 0
(-6250 4225);
DISPLAY 0.510638 (-6250 4225);
DISPLAY INVISIBLE (-6250 4225);
FORCEADD Q_CAP..1
(-6075 4375);
FORCEPROP 1 LAST LOCATION C1001
J 0
(-6025 4475);
DISPLAY 0.978723 (-6025 4475);
PAINT WHITE (-6025 4475);
FORCEPROP 0 LAST $SEC 1
J 0
(-6025 4525);
DISPLAY 0.680851 (-6025 4525);
PAINT MONO (-6025 4525);
DISPLAY INVISIBLE (-6025 4525);
FORCEPROP 0 LAST CDS_SEC 1
J 0
(-6025 4525);
DISPLAY 0.680851 (-6025 4525);
DISPLAY INVISIBLE (-6025 4525);
FORCEPROP 1 LASTPIN (-6075 4475) $PN 1
J 0
(-6065 4455);
DISPLAY 0.787234 (-6065 4455);
PAINT MONO (-6065 4455);
FORCEPROP 1 LASTPIN (-6075 4275) $PN 2
J 0
(-6065 4255);
DISPLAY 0.787234 (-6065 4255);
PAINT MONO (-6065 4255);
FORCEPROP 1 LAST VALUE 0.1UF
J 0
(-6025 4425);
DISPLAY 0.638298 (-6025 4425);
FORCEPROP 1 LAST TOLERANCE 10%
J 0
(-6025 4325);
DISPLAY 0.638298 (-6025 4325);
FORCEPROP 1 LAST VOLTAGE 10V
J 0
(-6025 4375);
DISPLAY 0.638298 (-6025 4375);
FORCEPROP 1 LAST PACK_TYPE C0201
J 0
(-6025 4225);
DISPLAY 0.638298 (-6025 4225);
FORCEPROP 1 LAST MATERIAL X7S
J 0
(-6025 4275);
DISPLAY 0.638298 (-6025 4275);
FORCEPROP 2 LAST CDS_LIB pure_quanta
J 0
(-6075 4375);
DISPLAY INVISIBLE (-6075 4375);
FORCEPROP 1 LAST PATH I25
J 0
(-6025 4525);
DISPLAY 0.978723 (-6025 4525);
PAINT WHITE (-6025 4525);
DISPLAY INVISIBLE (-6025 4525);
FORCEPROP 1 LAST PART_NUMBER CH4102K6E00
J 0
(-6025 4225);
DISPLAY 0.978723 (-6025 4225);
DISPLAY INVISIBLE (-6025 4225);
FORCEADD Q_CAP..1
(-5825 4375);
FORCEPROP 1 LAST LOCATION C1003
J 0
(-5775 4475);
DISPLAY 0.978723 (-5775 4475);
PAINT WHITE (-5775 4475);
FORCEPROP 0 LAST $SEC 1
J 0
(-5775 4525);
DISPLAY 0.680851 (-5775 4525);
PAINT MONO (-5775 4525);
DISPLAY INVISIBLE (-5775 4525);
FORCEPROP 0 LAST CDS_SEC 1
J 0
(-5775 4525);
DISPLAY 0.680851 (-5775 4525);
DISPLAY INVISIBLE (-5775 4525);
FORCEPROP 1 LASTPIN (-5825 4475) $PN 1
J 0
(-5815 4455);
DISPLAY 0.787234 (-5815 4455);
PAINT MONO (-5815 4455);
FORCEPROP 1 LASTPIN (-5825 4275) $PN 2
J 0
(-5815 4255);
DISPLAY 0.787234 (-5815 4255);
PAINT MONO (-5815 4255);
FORCEPROP 1 LAST TOLERANCE 10%
J 0
(-5775 4325);
DISPLAY 0.638298 (-5775 4325);
FORCEPROP 1 LAST VOLTAGE 10V
J 0
(-5775 4375);
DISPLAY 0.638298 (-5775 4375);
FORCEPROP 1 LAST PACK_TYPE C0201
J 0
(-5775 4225);
DISPLAY 0.638298 (-5775 4225);
FORCEPROP 1 LAST VALUE 0.1UF
J 0
(-5775 4425);
DISPLAY 0.638298 (-5775 4425);
FORCEPROP 1 LAST MATERIAL X7S
J 0
(-5775 4275);
DISPLAY 0.638298 (-5775 4275);
FORCEPROP 2 LAST CDS_LIB pure_quanta
J 0
(-5825 4375);
DISPLAY INVISIBLE (-5825 4375);
FORCEPROP 1 LAST PATH I26
J 0
(-5775 4525);
DISPLAY 0.978723 (-5775 4525);
PAINT WHITE (-5775 4525);
DISPLAY INVISIBLE (-5775 4525);
FORCEPROP 1 LAST PART_NUMBER CH4102K6E00
J 0
(-5775 4225);
DISPLAY 0.978723 (-5775 4225);
DISPLAY INVISIBLE (-5775 4225);
FORCEADD Q_CAP..1
(-5575 4375);
FORCEPROP 1 LAST LOCATION C1004
J 0
(-5525 4475);
DISPLAY 0.978723 (-5525 4475);
PAINT WHITE (-5525 4475);
FORCEPROP 0 LAST $SEC 1
J 0
(-5525 4525);
DISPLAY 0.680851 (-5525 4525);
PAINT MONO (-5525 4525);
DISPLAY INVISIBLE (-5525 4525);
FORCEPROP 0 LAST CDS_SEC 1
J 0
(-5525 4525);
DISPLAY 0.680851 (-5525 4525);
DISPLAY INVISIBLE (-5525 4525);
FORCEPROP 1 LASTPIN (-5575 4475) $PN 1
J 0
(-5565 4455);
DISPLAY 0.787234 (-5565 4455);
PAINT MONO (-5565 4455);
FORCEPROP 1 LASTPIN (-5575 4275) $PN 2
J 0
(-5565 4255);
DISPLAY 0.787234 (-5565 4255);
PAINT MONO (-5565 4255);
FORCEPROP 1 LAST TOLERANCE 10%
J 0
(-5525 4325);
DISPLAY 0.638298 (-5525 4325);
FORCEPROP 1 LAST VALUE 0.1UF
J 0
(-5525 4425);
DISPLAY 0.638298 (-5525 4425);
FORCEPROP 1 LAST VOLTAGE 10V
J 0
(-5525 4375);
DISPLAY 0.638298 (-5525 4375);
FORCEPROP 1 LAST PACK_TYPE C0201
J 0
(-5525 4225);
DISPLAY 0.638298 (-5525 4225);
FORCEPROP 1 LAST MATERIAL X7S
J 0
(-5525 4275);
DISPLAY 0.638298 (-5525 4275);
FORCEPROP 2 LAST CDS_LIB pure_quanta
J 0
(-5575 4375);
DISPLAY INVISIBLE (-5575 4375);
FORCEPROP 1 LAST PATH I27
J 0
(-5525 4525);
DISPLAY 0.978723 (-5525 4525);
PAINT WHITE (-5525 4525);
DISPLAY INVISIBLE (-5525 4525);
FORCEPROP 1 LAST PART_NUMBER CH4102K6E00
J 0
(-5525 4225);
DISPLAY 0.978723 (-5525 4225);
DISPLAY INVISIBLE (-5525 4225);
FORCEADD Q_CAP..1
(-5300 4375);
FORCEPROP 1 LAST LOCATION C1005
J 0
(-5250 4475);
DISPLAY 0.978723 (-5250 4475);
PAINT WHITE (-5250 4475);
FORCEPROP 0 LAST $SEC 1
J 0
(-5250 4525);
DISPLAY 0.680851 (-5250 4525);
PAINT MONO (-5250 4525);
DISPLAY INVISIBLE (-5250 4525);
FORCEPROP 0 LAST CDS_SEC 1
J 0
(-5250 4525);
DISPLAY 0.680851 (-5250 4525);
DISPLAY INVISIBLE (-5250 4525);
FORCEPROP 1 LASTPIN (-5300 4475) $PN 1
J 0
(-5290 4455);
DISPLAY 0.787234 (-5290 4455);
PAINT MONO (-5290 4455);
FORCEPROP 1 LASTPIN (-5300 4275) $PN 2
J 0
(-5290 4255);
DISPLAY 0.787234 (-5290 4255);
PAINT MONO (-5290 4255);
FORCEPROP 1 LAST PACK_TYPE C0201
J 0
(-5250 4225);
DISPLAY 0.638298 (-5250 4225);
FORCEPROP 1 LAST VALUE 0.1UF
J 0
(-5250 4425);
DISPLAY 0.638298 (-5250 4425);
FORCEPROP 1 LAST VOLTAGE 10V
J 0
(-5250 4375);
DISPLAY 0.638298 (-5250 4375);
FORCEPROP 1 LAST TOLERANCE 10%
J 0
(-5250 4325);
DISPLAY 0.638298 (-5250 4325);
FORCEPROP 1 LAST MATERIAL X7S
J 0
(-5250 4275);
DISPLAY 0.638298 (-5250 4275);
FORCEPROP 2 LAST CDS_LIB pure_quanta
J 0
(-5300 4375);
DISPLAY INVISIBLE (-5300 4375);
FORCEPROP 1 LAST PATH I28
J 0
(-5250 4525);
DISPLAY 0.978723 (-5250 4525);
PAINT WHITE (-5250 4525);
DISPLAY INVISIBLE (-5250 4525);
FORCEPROP 1 LAST PART_NUMBER CH4102K6E00
J 0
(-5250 4225);
DISPLAY 0.978723 (-5250 4225);
DISPLAY INVISIBLE (-5250 4225);
FORCEADD VCC_CORE..1
(-4450 6150);
FORCEPROP 3 LASTPIN (-4450 6100) SIG_NAME P0V9_CPU0_RT_2D\g
J 0
(-4440 6110);
DISPLAY 0.659574 (-4440 6110);
PAINT MONO (-4440 6110);
DISPLAY INVISIBLE (-4440 6110);
FORCEPROP 1 LAST HDL_POWER P0V9_CPU0_RT_2D
J 1
(-4450 6200);
DISPLAY 0.617021 (-4450 6200);
PAINT GREEN (-4450 6200);
FORCEPROP 2 LAST CDS_LIB pure_quanta_power
J 0
(-4450 6150);
DISPLAY INVISIBLE (-4450 6150);
FORCEPROP 1 LAST PATH I29
J 0
(-4400 6175);
DISPLAY 0.872340 (-4400 6175);
PAINT AQUA (-4400 6175);
DISPLAY INVISIBLE (-4400 6175);
FORCEADD UNIVERSAL_GND..1
(-6650 2875);
FORCEPROP 3 LASTPIN (-6650 2925) SIG_NAME GND\g
J 0
(-6640 2935);
DISPLAY 0.659574 (-6640 2935);
PAINT MONO (-6640 2935);
DISPLAY INVISIBLE (-6640 2935);
FORCEPROP 2 LAST CDS_LIB pure_quanta_power
J 0
(-6650 2875);
DISPLAY INVISIBLE (-6650 2875);
FORCEPROP 1 LAST HDL_POWER GND
J 1
(-6625 2800);
DISPLAY 0.872340 (-6625 2800);
PAINT GREEN (-6625 2800);
DISPLAY INVISIBLE (-6625 2800);
FORCEPROP 1 LAST PATH I3
J 0
(-6575 2875);
DISPLAY 0.872340 (-6575 2875);
PAINT AQUA (-6575 2875);
DISPLAY INVISIBLE (-6575 2875);
FORCEADD Q_CAP..1
(-3175 1325);
FORCEPROP 1 LAST LOCATION C1014
J 0
(-3125 1425);
DISPLAY 0.978723 (-3125 1425);
PAINT WHITE (-3125 1425);
FORCEPROP 0 LAST $SEC 1
J 0
(-3125 1475);
DISPLAY 0.680851 (-3125 1475);
PAINT MONO (-3125 1475);
DISPLAY INVISIBLE (-3125 1475);
FORCEPROP 0 LAST CDS_SEC 1
J 0
(-3125 1475);
DISPLAY 0.680851 (-3125 1475);
DISPLAY INVISIBLE (-3125 1475);
FORCEPROP 1 LASTPIN (-3175 1425) $PN 1
J 0
(-3165 1405);
DISPLAY 0.787234 (-3165 1405);
PAINT MONO (-3165 1405);
FORCEPROP 1 LASTPIN (-3175 1225) $PN 2
J 0
(-3165 1205);
DISPLAY 0.787234 (-3165 1205);
PAINT MONO (-3165 1205);
FORCEPROP 1 LAST TOLERANCE 10%
J 0
(-3125 1275);
DISPLAY 0.638298 (-3125 1275);
FORCEPROP 1 LAST VOLTAGE 10V
J 0
(-3125 1325);
DISPLAY 0.638298 (-3125 1325);
FORCEPROP 1 LAST VALUE 0.1UF
J 0
(-3125 1375);
DISPLAY 0.638298 (-3125 1375);
FORCEPROP 1 LAST PACK_TYPE C0201
J 0
(-3125 1175);
DISPLAY 0.638298 (-3125 1175);
FORCEPROP 1 LAST MATERIAL X7S
J 0
(-3125 1225);
DISPLAY 0.638298 (-3125 1225);
FORCEPROP 2 LAST CDS_LIB pure_quanta
J 0
(-3175 1325);
DISPLAY INVISIBLE (-3175 1325);
FORCEPROP 1 LAST PATH I30
J 0
(-3125 1475);
DISPLAY 0.978723 (-3125 1475);
PAINT WHITE (-3125 1475);
DISPLAY INVISIBLE (-3125 1475);
FORCEPROP 1 LAST PART_NUMBER CH4102K6E00
J 0
(-3125 1175);
DISPLAY 0.978723 (-3125 1175);
DISPLAY INVISIBLE (-3125 1175);
FORCEADD VCC_CORE..1
(-3300 1850);
FORCEPROP 3 LASTPIN (-3300 1800) SIG_NAME P0V9_CPU0_RT3_2A_2D\g
J 0
(-3290 1810);
DISPLAY 0.659574 (-3290 1810);
PAINT MONO (-3290 1810);
DISPLAY INVISIBLE (-3290 1810);
FORCEPROP 1 LAST HDL_POWER P0V9_CPU0_RT3_2A_2D
J 1
(-3300 1900);
DISPLAY 0.617021 (-3300 1900);
PAINT GREEN (-3300 1900);
FORCEPROP 2 LAST CDS_LIB pure_quanta_power
J 0
(-3300 1850);
DISPLAY INVISIBLE (-3300 1850);
FORCEPROP 1 LAST PATH I32
J 0
(-3250 1875);
DISPLAY 0.872340 (-3250 1875);
PAINT AQUA (-3250 1875);
DISPLAY INVISIBLE (-3250 1875);
FORCEADD UNIVERSAL_GND..1
(-2475 1000);
FORCEPROP 3 LASTPIN (-2475 1050) SIG_NAME GND\g
J 0
(-2465 1060);
DISPLAY 0.659574 (-2465 1060);
PAINT MONO (-2465 1060);
DISPLAY INVISIBLE (-2465 1060);
FORCEPROP 2 LAST CDS_LIB pure_quanta_power
J 0
(-2475 1000);
DISPLAY INVISIBLE (-2475 1000);
FORCEPROP 1 LAST HDL_POWER GND
J 1
(-2450 925);
DISPLAY 0.872340 (-2450 925);
PAINT GREEN (-2450 925);
DISPLAY INVISIBLE (-2450 925);
FORCEPROP 1 LAST PATH I34
J 0
(-2400 1000);
DISPLAY 0.872340 (-2400 1000);
PAINT AQUA (-2400 1000);
DISPLAY INVISIBLE (-2400 1000);
FORCEADD Q_CAP..1
(-2375 1325);
FORCEPROP 1 LAST LOCATION C1021
J 0
(-2325 1425);
DISPLAY 0.978723 (-2325 1425);
PAINT WHITE (-2325 1425);
FORCEPROP 0 LAST $SEC 1
J 0
(-2325 1475);
DISPLAY 0.680851 (-2325 1475);
PAINT MONO (-2325 1475);
DISPLAY INVISIBLE (-2325 1475);
FORCEPROP 0 LAST CDS_SEC 1
J 0
(-2325 1475);
DISPLAY 0.680851 (-2325 1475);
DISPLAY INVISIBLE (-2325 1475);
FORCEPROP 1 LASTPIN (-2375 1425) $PN 1
J 0
(-2365 1405);
DISPLAY 0.787234 (-2365 1405);
PAINT MONO (-2365 1405);
FORCEPROP 1 LASTPIN (-2375 1225) $PN 2
J 0
(-2365 1205);
DISPLAY 0.787234 (-2365 1205);
PAINT MONO (-2365 1205);
FORCEPROP 1 LAST VALUE 0.1UF
J 0
(-2325 1375);
DISPLAY 0.638298 (-2325 1375);
FORCEPROP 1 LAST TOLERANCE 10%
J 0
(-2325 1275);
DISPLAY 0.638298 (-2325 1275);
FORCEPROP 1 LAST VOLTAGE 10V
J 0
(-2325 1325);
DISPLAY 0.638298 (-2325 1325);
FORCEPROP 1 LAST MATERIAL X7S
J 0
(-2325 1225);
DISPLAY 0.638298 (-2325 1225);
FORCEPROP 1 LAST PACK_TYPE C0201
J 0
(-2325 1175);
DISPLAY 0.638298 (-2325 1175);
FORCEPROP 2 LAST CDS_LIB pure_quanta
J 0
(-2375 1325);
DISPLAY INVISIBLE (-2375 1325);
FORCEPROP 1 LAST PATH I35
J 0
(-2325 1475);
DISPLAY 0.978723 (-2325 1475);
PAINT WHITE (-2325 1475);
DISPLAY INVISIBLE (-2325 1475);
FORCEPROP 1 LAST PART_NUMBER CH4102K6E00
J 0
(-2325 1175);
DISPLAY 0.978723 (-2325 1175);
DISPLAY INVISIBLE (-2325 1175);
FORCEADD Q_RES..1
(-4075 2675);
FORCEPROP 1 LAST LOCATION R1095
J 0
(-4125 2725);
DISPLAY 0.978723 (-4125 2725);
FORCEPROP 0 LAST $SEC 1
J 0
(-4125 2775);
DISPLAY 0.680851 (-4125 2775);
PAINT MONO (-4125 2775);
DISPLAY INVISIBLE (-4125 2775);
FORCEPROP 0 LAST CDS_SEC 1
J 0
(-4125 2775);
DISPLAY 0.680851 (-4125 2775);
DISPLAY INVISIBLE (-4125 2775);
FORCEPROP 1 LASTPIN (-4175 2675) $PN 1
J 0
(-4163 2687);
DISPLAY 0.787234 (-4163 2687);
PAINT MONO (-4163 2687);
FORCEPROP 1 LASTPIN (-3975 2675) $PN 2
J 0
(-4013 2687);
DISPLAY 0.787234 (-4013 2687);
PAINT MONO (-4013 2687);
FORCEPROP 1 LAST MATERIAL CHIP
J 0
(-4075 2525);
DISPLAY 0.978723 (-4075 2525);
FORCEPROP 1 LAST VALUE 0
J 2
(-4100 2575);
DISPLAY 0.978723 (-4100 2575);
FORCEPROP 1 LAST TOLERANCE 5%
J 0
(-4075 2575);
DISPLAY 0.978723 (-4075 2575);
FORCEPROP 1 LAST WATTAGE 1/4W
J 2
(-4100 2525);
DISPLAY 0.978723 (-4100 2525);
FORCEPROP 1 LAST PACK_TYPE 0603LF
J 0
(-3825 2525);
DISPLAY 0.978723 (-3825 2525);
FORCEPROP 2 LAST CDS_LIB pure_quanta
J 0
(-4075 2675);
DISPLAY INVISIBLE (-4075 2675);
FORCEPROP 1 LAST PATH I36
J 0
(-4125 2825);
DISPLAY 0.978723 (-4125 2825);
PAINT WHITE (-4125 2825);
DISPLAY INVISIBLE (-4125 2825);
FORCEPROP 1 LAST PART_NUMBER CS00006J900
J 0
(-4300 2450);
DISPLAY 0.978723 (-4300 2450);
DISPLAY INVISIBLE (-4300 2450);
FORCEADD Q_CAP..1
(-3625 3125);
FORCEPROP 1 LAST LOCATION C1024
J 0
(-3575 3225);
DISPLAY 0.978723 (-3575 3225);
PAINT WHITE (-3575 3225);
FORCEPROP 0 LAST $SEC 1
J 0
(-3575 3275);
DISPLAY 0.680851 (-3575 3275);
PAINT MONO (-3575 3275);
DISPLAY INVISIBLE (-3575 3275);
FORCEPROP 0 LAST CDS_SEC 1
J 0
(-3575 3275);
DISPLAY 0.680851 (-3575 3275);
DISPLAY INVISIBLE (-3575 3275);
FORCEPROP 1 LASTPIN (-3625 3225) $PN 1
J 0
(-3615 3205);
DISPLAY 0.787234 (-3615 3205);
PAINT MONO (-3615 3205);
FORCEPROP 1 LASTPIN (-3625 3025) $PN 2
J 0
(-3615 3005);
DISPLAY 0.787234 (-3615 3005);
PAINT MONO (-3615 3005);
FORCEPROP 1 LAST VALUE 1UF
J 0
(-3575 3175);
DISPLAY 0.510638 (-3575 3175);
FORCEPROP 1 LAST PACK_TYPE 0201
J 0
(-3575 2975);
DISPLAY 0.510638 (-3575 2975);
FORCEPROP 1 LAST MATERIAL X6S
J 0
(-3575 3025);
DISPLAY 0.510638 (-3575 3025);
FORCEPROP 1 LAST TOLERANCE 20%
J 0
(-3575 3075);
DISPLAY 0.510638 (-3575 3075);
FORCEPROP 1 LAST VOLTAGE 4V
J 0
(-3575 3125);
DISPLAY 0.510638 (-3575 3125);
FORCEPROP 2 LAST CDS_LIB pure_quanta
J 0
(-3625 3125);
DISPLAY INVISIBLE (-3625 3125);
FORCEPROP 1 LAST PATH I37
J 0
(-3575 3275);
DISPLAY 0.978723 (-3575 3275);
PAINT WHITE (-3575 3275);
DISPLAY INVISIBLE (-3575 3275);
FORCEPROP 1 LAST PART_NUMBER CH-10KMEE00
J 0
(-3575 2975);
DISPLAY 0.510638 (-3575 2975);
DISPLAY INVISIBLE (-3575 2975);
FORCEADD Q_CAP..1
(-3400 3125);
FORCEPROP 1 LAST LOCATION C1027
J 0
(-3350 3225);
DISPLAY 0.978723 (-3350 3225);
PAINT WHITE (-3350 3225);
FORCEPROP 0 LAST $SEC 1
J 0
(-3350 3275);
DISPLAY 0.680851 (-3350 3275);
PAINT MONO (-3350 3275);
DISPLAY INVISIBLE (-3350 3275);
FORCEPROP 0 LAST CDS_SEC 1
J 0
(-3350 3275);
DISPLAY 0.680851 (-3350 3275);
DISPLAY INVISIBLE (-3350 3275);
FORCEPROP 1 LASTPIN (-3400 3225) $PN 1
J 0
(-3390 3205);
DISPLAY 0.787234 (-3390 3205);
PAINT MONO (-3390 3205);
FORCEPROP 1 LASTPIN (-3400 3025) $PN 2
J 0
(-3390 3005);
DISPLAY 0.787234 (-3390 3005);
PAINT MONO (-3390 3005);
FORCEPROP 1 LAST TOLERANCE 20%
J 0
(-3350 3075);
DISPLAY 0.510638 (-3350 3075);
FORCEPROP 1 LAST MATERIAL X6S
J 0
(-3350 3025);
DISPLAY 0.510638 (-3350 3025);
FORCEPROP 1 LAST VALUE 1UF
J 0
(-3350 3175);
DISPLAY 0.510638 (-3350 3175);
FORCEPROP 1 LAST VOLTAGE 4V
J 0
(-3350 3125);
DISPLAY 0.510638 (-3350 3125);
FORCEPROP 1 LAST PACK_TYPE 0201
J 0
(-3350 2975);
DISPLAY 0.510638 (-3350 2975);
FORCEPROP 2 LAST CDS_LIB pure_quanta
J 0
(-3400 3125);
DISPLAY INVISIBLE (-3400 3125);
FORCEPROP 1 LAST PATH I38
J 0
(-3350 3275);
DISPLAY 0.978723 (-3350 3275);
PAINT WHITE (-3350 3275);
DISPLAY INVISIBLE (-3350 3275);
FORCEPROP 1 LAST PART_NUMBER CH-10KMEE00
J 0
(-3350 2975);
DISPLAY 0.510638 (-3350 2975);
DISPLAY INVISIBLE (-3350 2975);
FORCEADD Q_CAP..1
(-3625 3750);
FORCEPROP 1 LAST LOCATION C1023
J 0
(-3575 3850);
DISPLAY 0.978723 (-3575 3850);
PAINT WHITE (-3575 3850);
FORCEPROP 0 LAST $SEC 1
J 0
(-3575 3900);
DISPLAY 0.680851 (-3575 3900);
PAINT MONO (-3575 3900);
DISPLAY INVISIBLE (-3575 3900);
FORCEPROP 0 LAST CDS_SEC 1
J 0
(-3575 3900);
DISPLAY 0.680851 (-3575 3900);
DISPLAY INVISIBLE (-3575 3900);
FORCEPROP 1 LASTPIN (-3625 3850) $PN 1
J 0
(-3615 3830);
DISPLAY 0.787234 (-3615 3830);
PAINT MONO (-3615 3830);
FORCEPROP 1 LASTPIN (-3625 3650) $PN 2
J 0
(-3615 3630);
DISPLAY 0.787234 (-3615 3630);
PAINT MONO (-3615 3630);
FORCEPROP 1 LAST VALUE 10UF
J 0
(-3575 3800);
DISPLAY 0.510638 (-3575 3800);
FORCEPROP 1 LAST PACK_TYPE C0402
J 0
(-3575 3600);
DISPLAY 0.510638 (-3575 3600);
FORCEPROP 1 LAST MATERIAL X6S
J 0
(-3575 3650);
DISPLAY 0.510638 (-3575 3650);
FORCEPROP 1 LAST VOLTAGE 6.3V
J 0
(-3575 3750);
DISPLAY 0.510638 (-3575 3750);
FORCEPROP 1 LAST TOLERANCE 20%
J 0
(-3575 3700);
DISPLAY 0.510638 (-3575 3700);
FORCEPROP 2 LAST CDS_LIB pure_quanta
J 0
(-3625 3750);
DISPLAY INVISIBLE (-3625 3750);
FORCEPROP 1 LAST PATH I39
J 0
(-3575 3900);
DISPLAY 0.978723 (-3575 3900);
PAINT WHITE (-3575 3900);
DISPLAY INVISIBLE (-3575 3900);
FORCEPROP 1 LAST PART_NUMBER CH6101MEB01
J 0
(-3575 3600);
DISPLAY 0.978723 (-3575 3600);
DISPLAY INVISIBLE (-3575 3600);
FORCEADD P1V0..1
(-7050 3675);
FORCEPROP 3 LASTPIN (-7050 3625) SIG_NAME P1V8_CPU0_RT3_1A_1D\g
J 0
(-7040 3635);
DISPLAY 0.659574 (-7040 3635);
PAINT MONO (-7040 3635);
DISPLAY INVISIBLE (-7040 3635);
FORCEPROP 1 LAST HDL_POWER P1V8_CPU0_RT3_1A_1D
J 1
(-7050 3725);
DISPLAY 0.489362 (-7050 3725);
PAINT SKYBLUE (-7050 3725);
FORCEPROP 2 LAST CDS_LIB pure_quanta_power
J 0
(-7050 3675);
DISPLAY INVISIBLE (-7050 3675);
FORCEPROP 1 LAST PATH I4
J 0
(-7000 3700);
DISPLAY 0.872340 (-7000 3700);
PAINT AQUA (-7000 3700);
DISPLAY INVISIBLE (-7000 3700);
FORCEADD Q_CAP..1
(-3400 3750);
FORCEPROP 1 LAST LOCATION C1036
J 0
(-3350 3850);
DISPLAY 0.978723 (-3350 3850);
PAINT WHITE (-3350 3850);
FORCEPROP 0 LAST $SEC 1
J 0
(-3350 3900);
DISPLAY 0.680851 (-3350 3900);
PAINT MONO (-3350 3900);
DISPLAY INVISIBLE (-3350 3900);
FORCEPROP 0 LAST CDS_SEC 1
J 0
(-3350 3900);
DISPLAY 0.680851 (-3350 3900);
DISPLAY INVISIBLE (-3350 3900);
FORCEPROP 1 LASTPIN (-3400 3850) $PN 1
J 0
(-3390 3830);
DISPLAY 0.787234 (-3390 3830);
PAINT MONO (-3390 3830);
FORCEPROP 1 LASTPIN (-3400 3650) $PN 2
J 0
(-3390 3630);
DISPLAY 0.787234 (-3390 3630);
PAINT MONO (-3390 3630);
FORCEPROP 1 LAST VOLTAGE 6.3V
J 0
(-3350 3750);
DISPLAY 0.510638 (-3350 3750);
FORCEPROP 1 LAST VALUE 10UF
J 0
(-3350 3800);
DISPLAY 0.510638 (-3350 3800);
FORCEPROP 1 LAST TOLERANCE 20%
J 0
(-3350 3700);
DISPLAY 0.510638 (-3350 3700);
FORCEPROP 1 LAST MATERIAL X6S
J 0
(-3350 3650);
DISPLAY 0.510638 (-3350 3650);
FORCEPROP 1 LAST PACK_TYPE C0402
J 0
(-3350 3600);
DISPLAY 0.510638 (-3350 3600);
FORCEPROP 2 LAST CDS_LIB pure_quanta
J 0
(-3400 3750);
DISPLAY INVISIBLE (-3400 3750);
FORCEPROP 1 LAST PATH I40
J 0
(-3350 3900);
DISPLAY 0.978723 (-3350 3900);
PAINT WHITE (-3350 3900);
DISPLAY INVISIBLE (-3350 3900);
FORCEPROP 1 LAST PART_NUMBER CH6101MEB01
J 0
(-3350 3600);
DISPLAY 0.978723 (-3350 3600);
DISPLAY INVISIBLE (-3350 3600);
FORCEADD Q_CAP..1
(-3350 2425);
FORCEPROP 1 LAST LOCATION C1010
J 0
(-3300 2525);
DISPLAY 0.978723 (-3300 2525);
PAINT WHITE (-3300 2525);
FORCEPROP 0 LAST $SEC 1
J 0
(-3300 2575);
DISPLAY 0.680851 (-3300 2575);
PAINT MONO (-3300 2575);
DISPLAY INVISIBLE (-3300 2575);
FORCEPROP 0 LAST CDS_SEC 1
J 0
(-3300 2575);
DISPLAY 0.680851 (-3300 2575);
DISPLAY INVISIBLE (-3300 2575);
FORCEPROP 1 LASTPIN (-3350 2525) $PN 1
J 0
(-3340 2505);
DISPLAY 0.787234 (-3340 2505);
PAINT MONO (-3340 2505);
FORCEPROP 1 LASTPIN (-3350 2325) $PN 2
J 0
(-3340 2305);
DISPLAY 0.787234 (-3340 2305);
PAINT MONO (-3340 2305);
FORCEPROP 1 LAST TOLERANCE 10%
J 0
(-3300 2375);
DISPLAY 0.638298 (-3300 2375);
FORCEPROP 1 LAST MATERIAL X7S
J 0
(-3300 2325);
DISPLAY 0.638298 (-3300 2325);
FORCEPROP 1 LAST PACK_TYPE C0201
J 0
(-3300 2275);
DISPLAY 0.638298 (-3300 2275);
FORCEPROP 1 LAST VALUE 0.1UF
J 0
(-3300 2475);
DISPLAY 0.638298 (-3300 2475);
FORCEPROP 1 LAST VOLTAGE 10V
J 0
(-3300 2425);
DISPLAY 0.638298 (-3300 2425);
FORCEPROP 2 LAST CDS_LIB pure_quanta
J 0
(-3350 2425);
DISPLAY INVISIBLE (-3350 2425);
FORCEPROP 1 LAST PATH I41
J 0
(-3300 2575);
DISPLAY 0.978723 (-3300 2575);
PAINT WHITE (-3300 2575);
DISPLAY INVISIBLE (-3300 2575);
FORCEPROP 1 LAST PART_NUMBER CH4102K6E00
J 0
(-3300 2275);
DISPLAY 0.978723 (-3300 2275);
DISPLAY INVISIBLE (-3300 2275);
FORCEADD Q_CAP..1
(-3050 2425);
FORCEPROP 1 LAST LOCATION C1052
J 0
(-3000 2525);
DISPLAY 0.978723 (-3000 2525);
PAINT WHITE (-3000 2525);
FORCEPROP 0 LAST $SEC 1
J 0
(-3000 2575);
DISPLAY 0.680851 (-3000 2575);
PAINT MONO (-3000 2575);
DISPLAY INVISIBLE (-3000 2575);
FORCEPROP 0 LAST CDS_SEC 1
J 0
(-3000 2575);
DISPLAY 0.680851 (-3000 2575);
DISPLAY INVISIBLE (-3000 2575);
FORCEPROP 1 LASTPIN (-3050 2525) $PN 1
J 0
(-3040 2505);
DISPLAY 0.787234 (-3040 2505);
PAINT MONO (-3040 2505);
FORCEPROP 1 LASTPIN (-3050 2325) $PN 2
J 0
(-3040 2305);
DISPLAY 0.787234 (-3040 2305);
PAINT MONO (-3040 2305);
FORCEPROP 1 LAST PACK_TYPE C0201
J 0
(-3000 2275);
DISPLAY 0.638298 (-3000 2275);
FORCEPROP 1 LAST TOLERANCE 10%
J 0
(-3000 2375);
DISPLAY 0.638298 (-3000 2375);
FORCEPROP 1 LAST VALUE 0.1UF
J 0
(-3000 2475);
DISPLAY 0.638298 (-3000 2475);
FORCEPROP 1 LAST MATERIAL X7S
J 0
(-3000 2325);
DISPLAY 0.638298 (-3000 2325);
FORCEPROP 1 LAST VOLTAGE 10V
J 0
(-3000 2425);
DISPLAY 0.638298 (-3000 2425);
FORCEPROP 2 LAST CDS_LIB pure_quanta
J 0
(-3050 2425);
DISPLAY INVISIBLE (-3050 2425);
FORCEPROP 1 LAST PATH I42
J 0
(-3000 2575);
DISPLAY 0.978723 (-3000 2575);
PAINT WHITE (-3000 2575);
DISPLAY INVISIBLE (-3000 2575);
FORCEPROP 1 LAST PART_NUMBER CH4102K6E00
J 0
(-3000 2275);
DISPLAY 0.978723 (-3000 2275);
DISPLAY INVISIBLE (-3000 2275);
FORCEADD Q_CAP..1
(-2825 2425);
FORCEPROP 1 LAST LOCATION C1055
J 0
(-2775 2525);
DISPLAY 0.978723 (-2775 2525);
PAINT WHITE (-2775 2525);
FORCEPROP 0 LAST $SEC 1
J 0
(-2775 2575);
DISPLAY 0.680851 (-2775 2575);
PAINT MONO (-2775 2575);
DISPLAY INVISIBLE (-2775 2575);
FORCEPROP 0 LAST CDS_SEC 1
J 0
(-2775 2575);
DISPLAY 0.680851 (-2775 2575);
DISPLAY INVISIBLE (-2775 2575);
FORCEPROP 1 LASTPIN (-2825 2525) $PN 1
J 0
(-2815 2505);
DISPLAY 0.787234 (-2815 2505);
PAINT MONO (-2815 2505);
FORCEPROP 1 LASTPIN (-2825 2325) $PN 2
J 0
(-2815 2305);
DISPLAY 0.787234 (-2815 2305);
PAINT MONO (-2815 2305);
FORCEPROP 1 LAST PACK_TYPE C0201
J 0
(-2775 2275);
DISPLAY 0.638298 (-2775 2275);
FORCEPROP 1 LAST VALUE 0.1UF
J 0
(-2775 2475);
DISPLAY 0.638298 (-2775 2475);
FORCEPROP 1 LAST VOLTAGE 10V
J 0
(-2775 2425);
DISPLAY 0.638298 (-2775 2425);
FORCEPROP 1 LAST TOLERANCE 10%
J 0
(-2775 2375);
DISPLAY 0.638298 (-2775 2375);
FORCEPROP 1 LAST MATERIAL X7S
J 0
(-2775 2325);
DISPLAY 0.638298 (-2775 2325);
FORCEPROP 2 LAST CDS_LIB pure_quanta
J 0
(-2825 2425);
DISPLAY INVISIBLE (-2825 2425);
FORCEPROP 1 LAST PATH I43
J 0
(-2775 2575);
DISPLAY 0.978723 (-2775 2575);
PAINT WHITE (-2775 2575);
DISPLAY INVISIBLE (-2775 2575);
FORCEPROP 1 LAST PART_NUMBER CH4102K6E00
J 0
(-2775 2275);
DISPLAY 0.978723 (-2775 2275);
DISPLAY INVISIBLE (-2775 2275);
FORCEADD Q_CAP..1
(-2575 2425);
FORCEPROP 1 LAST LOCATION C1035
J 0
(-2525 2525);
DISPLAY 0.978723 (-2525 2525);
PAINT WHITE (-2525 2525);
FORCEPROP 0 LAST $SEC 1
J 0
(-2525 2575);
DISPLAY 0.680851 (-2525 2575);
PAINT MONO (-2525 2575);
DISPLAY INVISIBLE (-2525 2575);
FORCEPROP 0 LAST CDS_SEC 1
J 0
(-2525 2575);
DISPLAY 0.680851 (-2525 2575);
DISPLAY INVISIBLE (-2525 2575);
FORCEPROP 1 LASTPIN (-2575 2525) $PN 1
J 0
(-2565 2505);
DISPLAY 0.787234 (-2565 2505);
PAINT MONO (-2565 2505);
FORCEPROP 1 LASTPIN (-2575 2325) $PN 2
J 0
(-2565 2305);
DISPLAY 0.787234 (-2565 2305);
PAINT MONO (-2565 2305);
FORCEPROP 1 LAST PACK_TYPE C0201
J 0
(-2525 2275);
DISPLAY 0.638298 (-2525 2275);
FORCEPROP 1 LAST VALUE 0.1UF
J 0
(-2525 2475);
DISPLAY 0.638298 (-2525 2475);
FORCEPROP 1 LAST VOLTAGE 10V
J 0
(-2525 2425);
DISPLAY 0.638298 (-2525 2425);
FORCEPROP 1 LAST MATERIAL X7S
J 0
(-2525 2325);
DISPLAY 0.638298 (-2525 2325);
FORCEPROP 1 LAST TOLERANCE 10%
J 0
(-2525 2375);
DISPLAY 0.638298 (-2525 2375);
FORCEPROP 2 LAST CDS_LIB pure_quanta
J 0
(-2575 2425);
DISPLAY INVISIBLE (-2575 2425);
FORCEPROP 1 LAST PATH I44
J 0
(-2525 2575);
DISPLAY 0.978723 (-2525 2575);
PAINT WHITE (-2525 2575);
DISPLAY INVISIBLE (-2525 2575);
FORCEPROP 1 LAST PART_NUMBER CH4102K6E00
J 0
(-2525 2275);
DISPLAY 0.978723 (-2525 2275);
DISPLAY INVISIBLE (-2525 2275);
FORCEADD Q_CAP..1
(-3150 3125);
FORCEPROP 1 LAST LOCATION C1031
J 0
(-3100 3225);
DISPLAY 0.978723 (-3100 3225);
PAINT WHITE (-3100 3225);
FORCEPROP 0 LAST $SEC 1
J 0
(-3100 3275);
DISPLAY 0.680851 (-3100 3275);
PAINT MONO (-3100 3275);
DISPLAY INVISIBLE (-3100 3275);
FORCEPROP 0 LAST CDS_SEC 1
J 0
(-3100 3275);
DISPLAY 0.680851 (-3100 3275);
DISPLAY INVISIBLE (-3100 3275);
FORCEPROP 1 LASTPIN (-3150 3225) $PN 1
J 0
(-3140 3205);
DISPLAY 0.787234 (-3140 3205);
PAINT MONO (-3140 3205);
FORCEPROP 1 LASTPIN (-3150 3025) $PN 2
J 0
(-3140 3005);
DISPLAY 0.787234 (-3140 3005);
PAINT MONO (-3140 3005);
FORCEPROP 1 LAST TOLERANCE 20%
J 0
(-3100 3075);
DISPLAY 0.510638 (-3100 3075);
FORCEPROP 1 LAST MATERIAL X6S
J 0
(-3100 3025);
DISPLAY 0.510638 (-3100 3025);
FORCEPROP 1 LAST VALUE 1UF
J 0
(-3100 3175);
DISPLAY 0.510638 (-3100 3175);
FORCEPROP 1 LAST PACK_TYPE 0201
J 0
(-3100 2975);
DISPLAY 0.510638 (-3100 2975);
FORCEPROP 1 LAST VOLTAGE 4V
J 0
(-3100 3125);
DISPLAY 0.510638 (-3100 3125);
FORCEPROP 2 LAST CDS_LIB pure_quanta
J 0
(-3150 3125);
DISPLAY INVISIBLE (-3150 3125);
FORCEPROP 1 LAST PATH I45
J 0
(-3100 3275);
DISPLAY 0.978723 (-3100 3275);
PAINT WHITE (-3100 3275);
DISPLAY INVISIBLE (-3100 3275);
FORCEPROP 1 LAST PART_NUMBER CH-10KMEE00
J 0
(-3100 2975);
DISPLAY 0.510638 (-3100 2975);
DISPLAY INVISIBLE (-3100 2975);
FORCEADD Q_CAP..1
(-2925 3125);
FORCEPROP 1 LAST LOCATION C1006
J 0
(-2875 3225);
DISPLAY 0.978723 (-2875 3225);
PAINT WHITE (-2875 3225);
FORCEPROP 0 LAST $SEC 1
J 0
(-2875 3275);
DISPLAY 0.680851 (-2875 3275);
PAINT MONO (-2875 3275);
DISPLAY INVISIBLE (-2875 3275);
FORCEPROP 0 LAST CDS_SEC 1
J 0
(-2875 3275);
DISPLAY 0.680851 (-2875 3275);
DISPLAY INVISIBLE (-2875 3275);
FORCEPROP 1 LASTPIN (-2925 3225) $PN 1
J 0
(-2915 3205);
DISPLAY 0.787234 (-2915 3205);
PAINT MONO (-2915 3205);
FORCEPROP 1 LASTPIN (-2925 3025) $PN 2
J 0
(-2915 3005);
DISPLAY 0.787234 (-2915 3005);
PAINT MONO (-2915 3005);
FORCEPROP 1 LAST PACK_TYPE 0201
J 0
(-2875 2975);
DISPLAY 0.510638 (-2875 2975);
FORCEPROP 1 LAST VOLTAGE 4V
J 0
(-2875 3125);
DISPLAY 0.510638 (-2875 3125);
FORCEPROP 1 LAST VALUE 1UF
J 0
(-2875 3175);
DISPLAY 0.510638 (-2875 3175);
FORCEPROP 1 LAST TOLERANCE 20%
J 0
(-2875 3075);
DISPLAY 0.510638 (-2875 3075);
FORCEPROP 1 LAST MATERIAL X6S
J 0
(-2875 3025);
DISPLAY 0.510638 (-2875 3025);
FORCEPROP 2 LAST CDS_LIB pure_quanta
J 0
(-2925 3125);
DISPLAY INVISIBLE (-2925 3125);
FORCEPROP 1 LAST PATH I46
J 0
(-2875 3275);
DISPLAY 0.978723 (-2875 3275);
PAINT WHITE (-2875 3275);
DISPLAY INVISIBLE (-2875 3275);
FORCEPROP 1 LAST PART_NUMBER CH-10KMEE00
J 0
(-2875 2975);
DISPLAY 0.510638 (-2875 2975);
DISPLAY INVISIBLE (-2875 2975);
FORCEADD Q_CAP..1
(-2950 3750);
FORCEPROP 1 LAST LOCATION C1034
J 0
(-2900 3850);
DISPLAY 0.978723 (-2900 3850);
PAINT WHITE (-2900 3850);
FORCEPROP 0 LAST $SEC 1
J 0
(-2900 3900);
DISPLAY 0.680851 (-2900 3900);
PAINT MONO (-2900 3900);
DISPLAY INVISIBLE (-2900 3900);
FORCEPROP 0 LAST CDS_SEC 1
J 0
(-2900 3900);
DISPLAY 0.680851 (-2900 3900);
DISPLAY INVISIBLE (-2900 3900);
FORCEPROP 1 LASTPIN (-2950 3850) $PN 1
J 0
(-2940 3830);
DISPLAY 0.787234 (-2940 3830);
PAINT MONO (-2940 3830);
FORCEPROP 1 LASTPIN (-2950 3650) $PN 2
J 0
(-2940 3630);
DISPLAY 0.787234 (-2940 3630);
PAINT MONO (-2940 3630);
FORCEPROP 1 LAST VOLTAGE 6.3V
J 0
(-2900 3750);
DISPLAY 0.510638 (-2900 3750);
FORCEPROP 1 LAST VALUE 4.7UF
J 0
(-2900 3800);
DISPLAY 0.510638 (-2900 3800);
FORCEPROP 1 LAST TOLERANCE 20%
J 0
(-2900 3700);
DISPLAY 0.510638 (-2900 3700);
FORCEPROP 1 LAST PACK_TYPE 0402
J 0
(-2900 3600);
DISPLAY 0.510638 (-2900 3600);
FORCEPROP 1 LAST MATERIAL X6S
J 0
(-2900 3650);
DISPLAY 0.510638 (-2900 3650);
FORCEPROP 2 LAST CDS_LIB pure_quanta
J 0
(-2950 3750);
DISPLAY INVISIBLE (-2950 3750);
FORCEPROP 1 LAST PATH I47
J 0
(-2900 3900);
DISPLAY 0.978723 (-2900 3900);
PAINT WHITE (-2900 3900);
DISPLAY INVISIBLE (-2900 3900);
FORCEPROP 1 LAST PART_NUMBER CH5471MEB01
J 0
(-2900 3600);
DISPLAY 0.978723 (-2900 3600);
DISPLAY INVISIBLE (-2900 3600);
FORCEADD Q_CAP..1
(-2675 3125);
FORCEPROP 1 LAST LOCATION C1039
J 0
(-2625 3225);
DISPLAY 0.978723 (-2625 3225);
PAINT WHITE (-2625 3225);
FORCEPROP 0 LAST $SEC 1
J 0
(-2625 3275);
DISPLAY 0.680851 (-2625 3275);
PAINT MONO (-2625 3275);
DISPLAY INVISIBLE (-2625 3275);
FORCEPROP 0 LAST CDS_SEC 1
J 0
(-2625 3275);
DISPLAY 0.680851 (-2625 3275);
DISPLAY INVISIBLE (-2625 3275);
FORCEPROP 1 LASTPIN (-2675 3225) $PN 1
J 0
(-2665 3205);
DISPLAY 0.787234 (-2665 3205);
PAINT MONO (-2665 3205);
FORCEPROP 1 LASTPIN (-2675 3025) $PN 2
J 0
(-2665 3005);
DISPLAY 0.787234 (-2665 3005);
PAINT MONO (-2665 3005);
FORCEPROP 1 LAST PACK_TYPE 0201
J 0
(-2625 2975);
DISPLAY 0.510638 (-2625 2975);
FORCEPROP 1 LAST VALUE 1UF
J 0
(-2625 3175);
DISPLAY 0.510638 (-2625 3175);
FORCEPROP 1 LAST MATERIAL X6S
J 0
(-2625 3025);
DISPLAY 0.510638 (-2625 3025);
FORCEPROP 1 LAST VOLTAGE 4V
J 0
(-2625 3125);
DISPLAY 0.510638 (-2625 3125);
FORCEPROP 1 LAST TOLERANCE 20%
J 0
(-2625 3075);
DISPLAY 0.510638 (-2625 3075);
FORCEPROP 2 LAST CDS_LIB pure_quanta
J 0
(-2675 3125);
DISPLAY INVISIBLE (-2675 3125);
FORCEPROP 1 LAST PATH I48
J 0
(-2625 3275);
DISPLAY 0.978723 (-2625 3275);
PAINT WHITE (-2625 3275);
DISPLAY INVISIBLE (-2625 3275);
FORCEPROP 1 LAST PART_NUMBER CH-10KMEE00
J 0
(-2625 2975);
DISPLAY 0.510638 (-2625 2975);
DISPLAY INVISIBLE (-2625 2975);
FORCEADD Q_CAP..1
(-2450 3100);
FORCEPROP 1 LAST LOCATION C1015
J 0
(-2400 3200);
DISPLAY 0.978723 (-2400 3200);
PAINT WHITE (-2400 3200);
FORCEPROP 0 LAST $SEC 1
J 0
(-2400 3250);
DISPLAY 0.680851 (-2400 3250);
PAINT MONO (-2400 3250);
DISPLAY INVISIBLE (-2400 3250);
FORCEPROP 0 LAST CDS_SEC 1
J 0
(-2400 3250);
DISPLAY 0.680851 (-2400 3250);
DISPLAY INVISIBLE (-2400 3250);
FORCEPROP 1 LASTPIN (-2450 3200) $PN 1
J 0
(-2440 3180);
DISPLAY 0.787234 (-2440 3180);
PAINT MONO (-2440 3180);
FORCEPROP 1 LASTPIN (-2450 3000) $PN 2
J 0
(-2440 2980);
DISPLAY 0.787234 (-2440 2980);
PAINT MONO (-2440 2980);
FORCEPROP 1 LAST MATERIAL X6S
J 0
(-2400 3000);
DISPLAY 0.510638 (-2400 3000);
FORCEPROP 1 LAST TOLERANCE 20%
J 0
(-2400 3050);
DISPLAY 0.510638 (-2400 3050);
FORCEPROP 1 LAST VALUE 1UF
J 0
(-2400 3150);
DISPLAY 0.510638 (-2400 3150);
FORCEPROP 1 LAST VOLTAGE 4V
J 0
(-2400 3100);
DISPLAY 0.510638 (-2400 3100);
FORCEPROP 1 LAST PACK_TYPE 0201
J 0
(-2400 2950);
DISPLAY 0.510638 (-2400 2950);
FORCEPROP 2 LAST CDS_LIB pure_quanta
J 0
(-2450 3100);
DISPLAY INVISIBLE (-2450 3100);
FORCEPROP 1 LAST PATH I49
J 0
(-2400 3250);
DISPLAY 0.978723 (-2400 3250);
PAINT WHITE (-2400 3250);
DISPLAY INVISIBLE (-2400 3250);
FORCEPROP 1 LAST PART_NUMBER CH-10KMEE00
J 0
(-2400 2950);
DISPLAY 0.510638 (-2400 2950);
DISPLAY INVISIBLE (-2400 2950);
FORCEADD Q_CAP..1
(-6925 3300);
FORCEPROP 1 LAST LOCATION C999
J 0
(-6875 3400);
DISPLAY 0.638298 (-6875 3400);
PAINT WHITE (-6875 3400);
FORCEPROP 0 LAST $SEC 1
J 0
(-6875 3450);
DISPLAY 0.680851 (-6875 3450);
PAINT MONO (-6875 3450);
DISPLAY INVISIBLE (-6875 3450);
FORCEPROP 0 LAST CDS_SEC 1
J 0
(-6875 3450);
DISPLAY 0.680851 (-6875 3450);
DISPLAY INVISIBLE (-6875 3450);
FORCEPROP 1 LASTPIN (-6925 3400) $PN 1
J 0
(-6915 3380);
DISPLAY 0.787234 (-6915 3380);
PAINT MONO (-6915 3380);
FORCEPROP 1 LASTPIN (-6925 3200) $PN 2
J 0
(-6915 3180);
DISPLAY 0.787234 (-6915 3180);
PAINT MONO (-6915 3180);
FORCEPROP 1 LAST VALUE 1UF
J 0
(-6875 3350);
DISPLAY 0.510638 (-6875 3350);
FORCEPROP 1 LAST MATERIAL X6S
J 0
(-6875 3200);
DISPLAY 0.510638 (-6875 3200);
FORCEPROP 1 LAST PACK_TYPE 0201
J 0
(-6875 3150);
DISPLAY 0.510638 (-6875 3150);
FORCEPROP 1 LAST TOLERANCE 20%
J 0
(-6875 3250);
DISPLAY 0.510638 (-6875 3250);
FORCEPROP 1 LAST VOLTAGE 4V
J 0
(-6875 3300);
DISPLAY 0.510638 (-6875 3300);
FORCEPROP 2 LAST CDS_LIB pure_quanta
J 0
(-6925 3300);
DISPLAY INVISIBLE (-6925 3300);
FORCEPROP 1 LAST PATH I5
J 0
(-6875 3450);
DISPLAY 0.978723 (-6875 3450);
PAINT WHITE (-6875 3450);
DISPLAY INVISIBLE (-6875 3450);
FORCEPROP 1 LAST PART_NUMBER CH-10KMEE00
J 0
(-6875 3150);
DISPLAY 0.510638 (-6875 3150);
DISPLAY INVISIBLE (-6875 3150);
FORCEADD Q_CAP..1
(-2700 3750);
FORCEPROP 1 LAST LOCATION C1054
J 0
(-2650 3850);
DISPLAY 0.978723 (-2650 3850);
PAINT WHITE (-2650 3850);
FORCEPROP 0 LAST $SEC 1
J 0
(-2650 3900);
DISPLAY 0.680851 (-2650 3900);
PAINT MONO (-2650 3900);
DISPLAY INVISIBLE (-2650 3900);
FORCEPROP 0 LAST CDS_SEC 1
J 0
(-2650 3900);
DISPLAY 0.680851 (-2650 3900);
DISPLAY INVISIBLE (-2650 3900);
FORCEPROP 1 LASTPIN (-2700 3850) $PN 1
J 0
(-2690 3830);
DISPLAY 0.787234 (-2690 3830);
PAINT MONO (-2690 3830);
FORCEPROP 1 LASTPIN (-2700 3650) $PN 2
J 0
(-2690 3630);
DISPLAY 0.787234 (-2690 3630);
PAINT MONO (-2690 3630);
FORCEPROP 1 LAST TOLERANCE 20%
J 0
(-2650 3700);
DISPLAY 0.510638 (-2650 3700);
FORCEPROP 1 LAST MATERIAL X6S
J 0
(-2650 3650);
DISPLAY 0.510638 (-2650 3650);
FORCEPROP 1 LAST PACK_TYPE 0402
J 0
(-2650 3600);
DISPLAY 0.510638 (-2650 3600);
FORCEPROP 1 LAST VOLTAGE 6.3V
J 0
(-2650 3750);
DISPLAY 0.510638 (-2650 3750);
FORCEPROP 1 LAST VALUE 4.7UF
J 0
(-2650 3800);
DISPLAY 0.510638 (-2650 3800);
FORCEPROP 2 LAST CDS_LIB pure_quanta
J 0
(-2700 3750);
DISPLAY INVISIBLE (-2700 3750);
FORCEPROP 1 LAST PATH I50
J 0
(-2650 3900);
DISPLAY 0.978723 (-2650 3900);
PAINT WHITE (-2650 3900);
DISPLAY INVISIBLE (-2650 3900);
FORCEPROP 1 LAST PART_NUMBER CH5471MEB01
J 0
(-2650 3600);
DISPLAY 0.978723 (-2650 3600);
DISPLAY INVISIBLE (-2650 3600);
FORCEADD Q_CAP..1
(-2475 3750);
FORCEPROP 1 LAST LOCATION C1056
J 0
(-2425 3850);
DISPLAY 0.978723 (-2425 3850);
PAINT WHITE (-2425 3850);
FORCEPROP 0 LAST $SEC 1
J 0
(-2425 3900);
DISPLAY 0.680851 (-2425 3900);
PAINT MONO (-2425 3900);
DISPLAY INVISIBLE (-2425 3900);
FORCEPROP 0 LAST CDS_SEC 1
J 0
(-2425 3900);
DISPLAY 0.680851 (-2425 3900);
DISPLAY INVISIBLE (-2425 3900);
FORCEPROP 1 LASTPIN (-2475 3850) $PN 1
J 0
(-2465 3830);
DISPLAY 0.787234 (-2465 3830);
PAINT MONO (-2465 3830);
FORCEPROP 1 LASTPIN (-2475 3650) $PN 2
J 0
(-2465 3630);
DISPLAY 0.787234 (-2465 3630);
PAINT MONO (-2465 3630);
FORCEPROP 1 LAST VOLTAGE 6.3V
J 0
(-2425 3750);
DISPLAY 0.510638 (-2425 3750);
FORCEPROP 1 LAST PACK_TYPE 0402
J 0
(-2425 3600);
DISPLAY 0.510638 (-2425 3600);
FORCEPROP 1 LAST TOLERANCE 20%
J 0
(-2425 3700);
DISPLAY 0.510638 (-2425 3700);
FORCEPROP 1 LAST VALUE 4.7UF
J 0
(-2425 3800);
DISPLAY 0.510638 (-2425 3800);
FORCEPROP 1 LAST MATERIAL X6S
J 0
(-2425 3650);
DISPLAY 0.510638 (-2425 3650);
FORCEPROP 2 LAST CDS_LIB pure_quanta
J 0
(-2475 3750);
DISPLAY INVISIBLE (-2475 3750);
FORCEPROP 1 LAST PATH I51
J 0
(-2425 3900);
DISPLAY 0.978723 (-2425 3900);
PAINT WHITE (-2425 3900);
DISPLAY INVISIBLE (-2425 3900);
FORCEPROP 1 LAST PART_NUMBER CH5471MEB01
J 0
(-2425 3600);
DISPLAY 0.978723 (-2425 3600);
DISPLAY INVISIBLE (-2425 3600);
FORCEADD Q_CAP..1
(-2325 2425);
FORCEPROP 1 LAST LOCATION C1008
J 0
(-2275 2525);
DISPLAY 0.978723 (-2275 2525);
PAINT WHITE (-2275 2525);
FORCEPROP 0 LAST $SEC 1
J 0
(-2275 2575);
DISPLAY 0.680851 (-2275 2575);
PAINT MONO (-2275 2575);
DISPLAY INVISIBLE (-2275 2575);
FORCEPROP 0 LAST CDS_SEC 1
J 0
(-2275 2575);
DISPLAY 0.680851 (-2275 2575);
DISPLAY INVISIBLE (-2275 2575);
FORCEPROP 1 LASTPIN (-2325 2525) $PN 1
J 0
(-2315 2505);
DISPLAY 0.787234 (-2315 2505);
PAINT MONO (-2315 2505);
FORCEPROP 1 LASTPIN (-2325 2325) $PN 2
J 0
(-2315 2305);
DISPLAY 0.787234 (-2315 2305);
PAINT MONO (-2315 2305);
FORCEPROP 1 LAST MATERIAL X7S
J 0
(-2275 2325);
DISPLAY 0.638298 (-2275 2325);
FORCEPROP 1 LAST PACK_TYPE C0201
J 0
(-2275 2275);
DISPLAY 0.638298 (-2275 2275);
FORCEPROP 1 LAST TOLERANCE 10%
J 0
(-2275 2375);
DISPLAY 0.638298 (-2275 2375);
FORCEPROP 1 LAST VOLTAGE 10V
J 0
(-2275 2425);
DISPLAY 0.638298 (-2275 2425);
FORCEPROP 1 LAST VALUE 0.1UF
J 0
(-2275 2475);
DISPLAY 0.638298 (-2275 2475);
FORCEPROP 2 LAST CDS_LIB pure_quanta
J 0
(-2325 2425);
DISPLAY INVISIBLE (-2325 2425);
FORCEPROP 1 LAST PATH I52
J 0
(-2275 2575);
DISPLAY 0.978723 (-2275 2575);
PAINT WHITE (-2275 2575);
DISPLAY INVISIBLE (-2275 2575);
FORCEPROP 1 LAST PART_NUMBER CH4102K6E00
J 0
(-2275 2275);
DISPLAY 0.978723 (-2275 2275);
DISPLAY INVISIBLE (-2275 2275);
FORCEADD Q_CAP..1
(-2050 2425);
FORCEPROP 1 LAST LOCATION C1011
J 0
(-2000 2525);
DISPLAY 0.978723 (-2000 2525);
PAINT WHITE (-2000 2525);
FORCEPROP 0 LAST $SEC 1
J 0
(-2000 2575);
DISPLAY 0.680851 (-2000 2575);
PAINT MONO (-2000 2575);
DISPLAY INVISIBLE (-2000 2575);
FORCEPROP 0 LAST CDS_SEC 1
J 0
(-2000 2575);
DISPLAY 0.680851 (-2000 2575);
DISPLAY INVISIBLE (-2000 2575);
FORCEPROP 1 LASTPIN (-2050 2525) $PN 1
J 0
(-2040 2505);
DISPLAY 0.787234 (-2040 2505);
PAINT MONO (-2040 2505);
FORCEPROP 1 LASTPIN (-2050 2325) $PN 2
J 0
(-2040 2305);
DISPLAY 0.787234 (-2040 2305);
PAINT MONO (-2040 2305);
FORCEPROP 1 LAST PACK_TYPE C0201
J 0
(-2000 2275);
DISPLAY 0.638298 (-2000 2275);
FORCEPROP 1 LAST MATERIAL X7S
J 0
(-2000 2325);
DISPLAY 0.638298 (-2000 2325);
FORCEPROP 1 LAST VOLTAGE 10V
J 0
(-2000 2425);
DISPLAY 0.638298 (-2000 2425);
FORCEPROP 1 LAST VALUE 0.1UF
J 0
(-2000 2475);
DISPLAY 0.638298 (-2000 2475);
FORCEPROP 1 LAST TOLERANCE 10%
J 0
(-2000 2375);
DISPLAY 0.638298 (-2000 2375);
FORCEPROP 2 LAST CDS_LIB pure_quanta
J 0
(-2050 2425);
DISPLAY INVISIBLE (-2050 2425);
FORCEPROP 1 LAST PATH I53
J 0
(-2000 2575);
DISPLAY 0.978723 (-2000 2575);
PAINT WHITE (-2000 2575);
DISPLAY INVISIBLE (-2000 2575);
FORCEPROP 1 LAST PART_NUMBER CH4102K6E00
J 0
(-2000 2275);
DISPLAY 0.978723 (-2000 2275);
DISPLAY INVISIBLE (-2000 2275);
FORCEADD Q_CAP..1
(-1775 2425);
FORCEPROP 1 LAST LOCATION C1043
J 0
(-1725 2525);
DISPLAY 0.978723 (-1725 2525);
PAINT WHITE (-1725 2525);
FORCEPROP 0 LAST $SEC 1
J 0
(-1725 2575);
DISPLAY 0.680851 (-1725 2575);
PAINT MONO (-1725 2575);
DISPLAY INVISIBLE (-1725 2575);
FORCEPROP 0 LAST CDS_SEC 1
J 0
(-1725 2575);
DISPLAY 0.680851 (-1725 2575);
DISPLAY INVISIBLE (-1725 2575);
FORCEPROP 1 LASTPIN (-1775 2525) $PN 1
J 0
(-1765 2505);
DISPLAY 0.787234 (-1765 2505);
PAINT MONO (-1765 2505);
FORCEPROP 1 LASTPIN (-1775 2325) $PN 2
J 0
(-1765 2305);
DISPLAY 0.787234 (-1765 2305);
PAINT MONO (-1765 2305);
FORCEPROP 1 LAST MATERIAL X7S
J 0
(-1725 2325);
DISPLAY 0.638298 (-1725 2325);
FORCEPROP 1 LAST VALUE 0.1UF
J 0
(-1725 2475);
DISPLAY 0.638298 (-1725 2475);
FORCEPROP 1 LAST VOLTAGE 10V
J 0
(-1725 2425);
DISPLAY 0.638298 (-1725 2425);
FORCEPROP 1 LAST TOLERANCE 10%
J 0
(-1725 2375);
DISPLAY 0.638298 (-1725 2375);
FORCEPROP 1 LAST PACK_TYPE C0201
J 0
(-1725 2275);
DISPLAY 0.638298 (-1725 2275);
FORCEPROP 2 LAST CDS_LIB pure_quanta
J 0
(-1775 2425);
DISPLAY INVISIBLE (-1775 2425);
FORCEPROP 1 LAST PATH I54
J 0
(-1725 2575);
DISPLAY 0.978723 (-1725 2575);
PAINT WHITE (-1725 2575);
DISPLAY INVISIBLE (-1725 2575);
FORCEPROP 1 LAST PART_NUMBER CH4102K6E00
J 0
(-1725 2275);
DISPLAY 0.978723 (-1725 2275);
DISPLAY INVISIBLE (-1725 2275);
FORCEADD UNIVERSAL_GND..1
(-1525 2000);
FORCEPROP 3 LASTPIN (-1525 2050) SIG_NAME GND\g
J 0
(-1515 2060);
DISPLAY 0.659574 (-1515 2060);
PAINT MONO (-1515 2060);
DISPLAY INVISIBLE (-1515 2060);
FORCEPROP 2 LAST CDS_LIB pure_quanta_power
J 0
(-1525 2000);
DISPLAY INVISIBLE (-1525 2000);
FORCEPROP 1 LAST HDL_POWER GND
J 1
(-1500 1925);
DISPLAY 0.872340 (-1500 1925);
PAINT GREEN (-1500 1925);
DISPLAY INVISIBLE (-1500 1925);
FORCEPROP 1 LAST PATH I55
J 0
(-1450 2000);
DISPLAY 0.872340 (-1450 2000);
PAINT AQUA (-1450 2000);
DISPLAY INVISIBLE (-1450 2000);
FORCEADD Q_CAP..1
(-1525 2425);
FORCEPROP 1 LAST LOCATION C1047
J 0
(-1475 2525);
DISPLAY 0.978723 (-1475 2525);
PAINT WHITE (-1475 2525);
FORCEPROP 0 LAST $SEC 1
J 0
(-1475 2575);
DISPLAY 0.680851 (-1475 2575);
PAINT MONO (-1475 2575);
DISPLAY INVISIBLE (-1475 2575);
FORCEPROP 0 LAST CDS_SEC 1
J 0
(-1475 2575);
DISPLAY 0.680851 (-1475 2575);
DISPLAY INVISIBLE (-1475 2575);
FORCEPROP 1 LASTPIN (-1525 2525) $PN 1
J 0
(-1515 2505);
DISPLAY 0.787234 (-1515 2505);
PAINT MONO (-1515 2505);
FORCEPROP 1 LASTPIN (-1525 2325) $PN 2
J 0
(-1515 2305);
DISPLAY 0.787234 (-1515 2305);
PAINT MONO (-1515 2305);
FORCEPROP 1 LAST MATERIAL X7S
J 0
(-1475 2325);
DISPLAY 0.638298 (-1475 2325);
FORCEPROP 1 LAST VOLTAGE 10V
J 0
(-1475 2425);
DISPLAY 0.638298 (-1475 2425);
FORCEPROP 1 LAST TOLERANCE 10%
J 0
(-1475 2375);
DISPLAY 0.638298 (-1475 2375);
FORCEPROP 1 LAST PACK_TYPE C0201
J 0
(-1475 2275);
DISPLAY 0.638298 (-1475 2275);
FORCEPROP 1 LAST VALUE 0.1UF
J 0
(-1475 2475);
DISPLAY 0.638298 (-1475 2475);
FORCEPROP 2 LAST CDS_LIB pure_quanta
J 0
(-1525 2425);
DISPLAY INVISIBLE (-1525 2425);
FORCEPROP 1 LAST PATH I56
J 0
(-1475 2575);
DISPLAY 0.978723 (-1475 2575);
PAINT WHITE (-1475 2575);
DISPLAY INVISIBLE (-1475 2575);
FORCEPROP 1 LAST PART_NUMBER CH4102K6E00
J 0
(-1475 2275);
DISPLAY 0.978723 (-1475 2275);
DISPLAY INVISIBLE (-1475 2275);
FORCEADD Q_CAP..1
(-2225 3100);
FORCEPROP 1 LAST LOCATION C1019
J 0
(-2175 3200);
DISPLAY 0.978723 (-2175 3200);
PAINT WHITE (-2175 3200);
FORCEPROP 0 LAST $SEC 1
J 0
(-2175 3250);
DISPLAY 0.680851 (-2175 3250);
PAINT MONO (-2175 3250);
DISPLAY INVISIBLE (-2175 3250);
FORCEPROP 0 LAST CDS_SEC 1
J 0
(-2175 3250);
DISPLAY 0.680851 (-2175 3250);
DISPLAY INVISIBLE (-2175 3250);
FORCEPROP 1 LASTPIN (-2225 3200) $PN 1
J 0
(-2215 3180);
DISPLAY 0.787234 (-2215 3180);
PAINT MONO (-2215 3180);
FORCEPROP 1 LASTPIN (-2225 3000) $PN 2
J 0
(-2215 2980);
DISPLAY 0.787234 (-2215 2980);
PAINT MONO (-2215 2980);
FORCEPROP 1 LAST VOLTAGE 4V
J 0
(-2175 3100);
DISPLAY 0.510638 (-2175 3100);
FORCEPROP 1 LAST VALUE 1UF
J 0
(-2175 3150);
DISPLAY 0.510638 (-2175 3150);
FORCEPROP 1 LAST TOLERANCE 20%
J 0
(-2175 3050);
DISPLAY 0.510638 (-2175 3050);
FORCEPROP 1 LAST MATERIAL X6S
J 0
(-2175 3000);
DISPLAY 0.510638 (-2175 3000);
FORCEPROP 1 LAST PACK_TYPE 0201
J 0
(-2175 2950);
DISPLAY 0.510638 (-2175 2950);
FORCEPROP 2 LAST CDS_LIB pure_quanta
J 0
(-2225 3100);
DISPLAY INVISIBLE (-2225 3100);
FORCEPROP 1 LAST PATH I57
J 0
(-2175 3250);
DISPLAY 0.978723 (-2175 3250);
PAINT WHITE (-2175 3250);
DISPLAY INVISIBLE (-2175 3250);
FORCEPROP 1 LAST PART_NUMBER CH-10KMEE00
J 0
(-2175 2950);
DISPLAY 0.510638 (-2175 2950);
DISPLAY INVISIBLE (-2175 2950);
FORCEADD Q_CAP..1
(-2250 3750);
FORCEPROP 1 LAST LOCATION C1046
J 0
(-2200 3850);
DISPLAY 0.978723 (-2200 3850);
PAINT WHITE (-2200 3850);
FORCEPROP 0 LAST $SEC 1
J 0
(-2200 3900);
DISPLAY 0.680851 (-2200 3900);
PAINT MONO (-2200 3900);
DISPLAY INVISIBLE (-2200 3900);
FORCEPROP 0 LAST CDS_SEC 1
J 0
(-2200 3900);
DISPLAY 0.680851 (-2200 3900);
DISPLAY INVISIBLE (-2200 3900);
FORCEPROP 1 LASTPIN (-2250 3850) $PN 1
J 0
(-2240 3830);
DISPLAY 0.787234 (-2240 3830);
PAINT MONO (-2240 3830);
FORCEPROP 1 LASTPIN (-2250 3650) $PN 2
J 0
(-2240 3630);
DISPLAY 0.787234 (-2240 3630);
PAINT MONO (-2240 3630);
FORCEPROP 1 LAST VALUE 1UF
J 0
(-2200 3800);
DISPLAY 0.510638 (-2200 3800);
FORCEPROP 1 LAST VOLTAGE 4V
J 0
(-2200 3750);
DISPLAY 0.510638 (-2200 3750);
FORCEPROP 1 LAST MATERIAL X6S
J 0
(-2200 3650);
DISPLAY 0.510638 (-2200 3650);
FORCEPROP 1 LAST TOLERANCE 20%
J 0
(-2200 3700);
DISPLAY 0.510638 (-2200 3700);
FORCEPROP 1 LAST PACK_TYPE 0201
J 0
(-2200 3600);
DISPLAY 0.510638 (-2200 3600);
FORCEPROP 2 LAST CDS_LIB pure_quanta
J 0
(-2250 3750);
DISPLAY INVISIBLE (-2250 3750);
FORCEPROP 1 LAST PATH I59
J 0
(-2200 3900);
DISPLAY 0.978723 (-2200 3900);
PAINT WHITE (-2200 3900);
DISPLAY INVISIBLE (-2200 3900);
FORCEPROP 1 LAST PART_NUMBER CH-10KMEE00
J 0
(-2200 3600);
DISPLAY 0.510638 (-2200 3600);
DISPLAY INVISIBLE (-2200 3600);
FORCEADD Q_CAP..1
(-6650 3275);
FORCEPROP 1 LAST LOCATION C1002
J 0
(-6600 3375);
DISPLAY 0.978723 (-6600 3375);
PAINT WHITE (-6600 3375);
FORCEPROP 0 LAST $SEC 1
J 0
(-6600 3425);
DISPLAY 0.680851 (-6600 3425);
PAINT MONO (-6600 3425);
DISPLAY INVISIBLE (-6600 3425);
FORCEPROP 0 LAST CDS_SEC 1
J 0
(-6600 3425);
DISPLAY 0.680851 (-6600 3425);
DISPLAY INVISIBLE (-6600 3425);
FORCEPROP 1 LASTPIN (-6650 3375) $PN 1
J 0
(-6640 3355);
DISPLAY 0.787234 (-6640 3355);
PAINT MONO (-6640 3355);
FORCEPROP 1 LASTPIN (-6650 3175) $PN 2
J 0
(-6640 3155);
DISPLAY 0.787234 (-6640 3155);
PAINT MONO (-6640 3155);
FORCEPROP 1 LAST VOLTAGE 10V
J 0
(-6600 3275);
DISPLAY 0.638298 (-6600 3275);
FORCEPROP 1 LAST TOLERANCE 10%
J 0
(-6600 3225);
DISPLAY 0.638298 (-6600 3225);
FORCEPROP 1 LAST MATERIAL X7S
J 0
(-6600 3175);
DISPLAY 0.638298 (-6600 3175);
FORCEPROP 1 LAST PACK_TYPE C0201
J 0
(-6600 3125);
DISPLAY 0.638298 (-6600 3125);
FORCEPROP 1 LAST VALUE 0.1UF
J 0
(-6600 3325);
DISPLAY 0.638298 (-6600 3325);
FORCEPROP 2 LAST CDS_LIB pure_quanta
J 0
(-6650 3275);
DISPLAY INVISIBLE (-6650 3275);
FORCEPROP 1 LAST PATH I6
J 0
(-6600 3425);
DISPLAY 0.978723 (-6600 3425);
PAINT WHITE (-6600 3425);
DISPLAY INVISIBLE (-6600 3425);
FORCEPROP 1 LAST PART_NUMBER CH4102K6E00
J 0
(-6600 3125);
DISPLAY 0.978723 (-6600 3125);
DISPLAY INVISIBLE (-6600 3125);
FORCEADD Q_CAP..1
(-2025 3750);
FORCEPROP 1 LAST LOCATION C1050
J 0
(-1975 3850);
DISPLAY 0.978723 (-1975 3850);
PAINT WHITE (-1975 3850);
FORCEPROP 0 LAST $SEC 1
J 0
(-1975 3900);
DISPLAY 0.680851 (-1975 3900);
PAINT MONO (-1975 3900);
DISPLAY INVISIBLE (-1975 3900);
FORCEPROP 0 LAST CDS_SEC 1
J 0
(-1975 3900);
DISPLAY 0.680851 (-1975 3900);
DISPLAY INVISIBLE (-1975 3900);
FORCEPROP 1 LASTPIN (-2025 3850) $PN 1
J 0
(-2015 3830);
DISPLAY 0.787234 (-2015 3830);
PAINT MONO (-2015 3830);
FORCEPROP 1 LASTPIN (-2025 3650) $PN 2
J 0
(-2015 3630);
DISPLAY 0.787234 (-2015 3630);
PAINT MONO (-2015 3630);
FORCEPROP 1 LAST VALUE 1UF
J 0
(-1975 3800);
DISPLAY 0.510638 (-1975 3800);
FORCEPROP 1 LAST VOLTAGE 4V
J 0
(-1975 3750);
DISPLAY 0.510638 (-1975 3750);
FORCEPROP 1 LAST TOLERANCE 20%
J 0
(-1975 3700);
DISPLAY 0.510638 (-1975 3700);
FORCEPROP 1 LAST MATERIAL X6S
J 0
(-1975 3650);
DISPLAY 0.510638 (-1975 3650);
FORCEPROP 1 LAST PACK_TYPE 0201
J 0
(-1975 3600);
DISPLAY 0.510638 (-1975 3600);
FORCEPROP 2 LAST CDS_LIB pure_quanta
J 0
(-2025 3750);
DISPLAY INVISIBLE (-2025 3750);
FORCEPROP 1 LAST PATH I60
J 0
(-1975 3900);
DISPLAY 0.978723 (-1975 3900);
PAINT WHITE (-1975 3900);
DISPLAY INVISIBLE (-1975 3900);
FORCEPROP 1 LAST PART_NUMBER CH-10KMEE00
J 0
(-1975 3600);
DISPLAY 0.510638 (-1975 3600);
DISPLAY INVISIBLE (-1975 3600);
FORCEADD Q_CAP..1
(-1800 3750);
FORCEPROP 1 LAST LOCATION C1013
J 0
(-1750 3850);
DISPLAY 0.978723 (-1750 3850);
PAINT WHITE (-1750 3850);
FORCEPROP 0 LAST $SEC 1
J 0
(-1750 3900);
DISPLAY 0.680851 (-1750 3900);
PAINT MONO (-1750 3900);
DISPLAY INVISIBLE (-1750 3900);
FORCEPROP 0 LAST CDS_SEC 1
J 0
(-1750 3900);
DISPLAY 0.680851 (-1750 3900);
DISPLAY INVISIBLE (-1750 3900);
FORCEPROP 1 LASTPIN (-1800 3850) $PN 1
J 0
(-1790 3830);
DISPLAY 0.787234 (-1790 3830);
PAINT MONO (-1790 3830);
FORCEPROP 1 LASTPIN (-1800 3650) $PN 2
J 0
(-1790 3630);
DISPLAY 0.787234 (-1790 3630);
PAINT MONO (-1790 3630);
FORCEPROP 1 LAST VOLTAGE 4V
J 0
(-1750 3750);
DISPLAY 0.510638 (-1750 3750);
FORCEPROP 1 LAST TOLERANCE 20%
J 0
(-1750 3700);
DISPLAY 0.510638 (-1750 3700);
FORCEPROP 1 LAST PACK_TYPE 0201
J 0
(-1750 3600);
DISPLAY 0.510638 (-1750 3600);
FORCEPROP 1 LAST VALUE 1UF
J 0
(-1750 3800);
DISPLAY 0.510638 (-1750 3800);
FORCEPROP 1 LAST MATERIAL X6S
J 0
(-1750 3650);
DISPLAY 0.510638 (-1750 3650);
FORCEPROP 2 LAST CDS_LIB pure_quanta
J 0
(-1800 3750);
DISPLAY INVISIBLE (-1800 3750);
FORCEPROP 1 LAST PATH I62
J 0
(-1750 3900);
DISPLAY 0.978723 (-1750 3900);
PAINT WHITE (-1750 3900);
DISPLAY INVISIBLE (-1750 3900);
FORCEPROP 1 LAST PART_NUMBER CH-10KMEE00
J 0
(-1750 3600);
DISPLAY 0.510638 (-1750 3600);
DISPLAY INVISIBLE (-1750 3600);
FORCEADD Q_CAP..1
(-1550 3750);
FORCEPROP 1 LAST LOCATION C1017
J 0
(-1500 3850);
DISPLAY 0.978723 (-1500 3850);
PAINT WHITE (-1500 3850);
FORCEPROP 0 LAST $SEC 1
J 0
(-1500 3900);
DISPLAY 0.680851 (-1500 3900);
PAINT MONO (-1500 3900);
DISPLAY INVISIBLE (-1500 3900);
FORCEPROP 0 LAST CDS_SEC 1
J 0
(-1500 3900);
DISPLAY 0.680851 (-1500 3900);
DISPLAY INVISIBLE (-1500 3900);
FORCEPROP 1 LASTPIN (-1550 3850) $PN 1
J 0
(-1540 3830);
DISPLAY 0.787234 (-1540 3830);
PAINT MONO (-1540 3830);
FORCEPROP 1 LASTPIN (-1550 3650) $PN 2
J 0
(-1540 3630);
DISPLAY 0.787234 (-1540 3630);
PAINT MONO (-1540 3630);
FORCEPROP 1 LAST PACK_TYPE 0201
J 0
(-1500 3600);
DISPLAY 0.510638 (-1500 3600);
FORCEPROP 1 LAST TOLERANCE 20%
J 0
(-1500 3700);
DISPLAY 0.510638 (-1500 3700);
FORCEPROP 1 LAST VOLTAGE 4V
J 0
(-1500 3750);
DISPLAY 0.510638 (-1500 3750);
FORCEPROP 1 LAST VALUE 1UF
J 0
(-1500 3800);
DISPLAY 0.510638 (-1500 3800);
FORCEPROP 1 LAST MATERIAL X6S
J 0
(-1500 3650);
DISPLAY 0.510638 (-1500 3650);
FORCEPROP 2 LAST CDS_LIB pure_quanta
J 0
(-1550 3750);
DISPLAY INVISIBLE (-1550 3750);
FORCEPROP 1 LAST PATH I63
J 0
(-1500 3900);
DISPLAY 0.978723 (-1500 3900);
PAINT WHITE (-1500 3900);
DISPLAY INVISIBLE (-1500 3900);
FORCEPROP 1 LAST PART_NUMBER CH-10KMEE00
J 0
(-1500 3600);
DISPLAY 0.510638 (-1500 3600);
DISPLAY INVISIBLE (-1500 3600);
FORCEADD UNIVERSAL_GND..1
(-1025 2700);
FORCEPROP 3 LASTPIN (-1025 2750) SIG_NAME GND\g
J 0
(-1015 2760);
DISPLAY 0.659574 (-1015 2760);
PAINT MONO (-1015 2760);
DISPLAY INVISIBLE (-1015 2760);
FORCEPROP 2 LAST CDS_LIB pure_quanta_power
J 0
(-1025 2700);
DISPLAY INVISIBLE (-1025 2700);
FORCEPROP 1 LAST HDL_POWER GND
J 1
(-1000 2625);
DISPLAY 0.872340 (-1000 2625);
PAINT GREEN (-1000 2625);
DISPLAY INVISIBLE (-1000 2625);
FORCEPROP 1 LAST PATH I64
J 0
(-950 2700);
DISPLAY 0.872340 (-950 2700);
PAINT AQUA (-950 2700);
DISPLAY INVISIBLE (-950 2700);
FORCEADD Q_INDUCTOR..1
(-3975 4650);
FORCEPROP 1 LAST LOCATION L23
J 0
(-4100 4810);
DISPLAY 0.723404 (-4100 4810);
PAINT GREEN (-4100 4810);
FORCEPROP 0 LAST $SEC 1
J 0
(-4100 4950);
DISPLAY 0.680851 (-4100 4950);
PAINT MONO (-4100 4950);
DISPLAY INVISIBLE (-4100 4950);
FORCEPROP 0 LAST CDS_SEC 1
J 0
(-4100 4950);
DISPLAY 0.680851 (-4100 4950);
DISPLAY INVISIBLE (-4100 4950);
FORCEPROP 0 LASTPIN (-4075 4625) $PN 1
J 2
(-4085 4635);
DISPLAY 0.680851 (-4085 4635);
PAINT MONO (-4085 4635);
FORCEPROP 0 LASTPIN (-3875 4625) $PN 2
J 0
(-3865 4635);
DISPLAY 0.680851 (-3865 4635);
PAINT MONO (-3865 4635);
FORCEPROP 2 LAST VALUE 100NH/16A
J 0
(-4100 4900);
DISPLAY 0.680851 (-4100 4900);
FORCEPROP 2 LAST PACK_TYPE SMLF
J 0
(-4100 4850);
DISPLAY 0.680851 (-4100 4850);
FORCEPROP 1 LAST MATERIAL IND
J 0
(-4100 4705);
DISPLAY 0.723404 (-4100 4705);
PAINT GREEN (-4100 4705);
FORCEPROP 2 LAST CDS_LIB pure_quanta
J 0
(-3975 4650);
DISPLAY INVISIBLE (-3975 4650);
FORCEPROP 1 LAST NEEDS_NO_SIZE TRUE
J 0
(-3975 4650);
DISPLAY 0.468085 (-3975 4650);
PAINT GREEN (-3975 4650);
DISPLAY INVISIBLE (-3975 4650);
FORCEPROP 1 LAST PATH I65
J 0
(-3900 4705);
DISPLAY 0.723404 (-3900 4705);
PAINT GREEN (-3900 4705);
DISPLAY INVISIBLE (-3900 4705);
FORCEPROP 1 LAST PART_NUMBER CV+10G0MZ04
J 0
(-4100 4760);
DISPLAY 0.723404 (-4100 4760);
PAINT GREEN (-4100 4760);
DISPLAY INVISIBLE (-4100 4760);
FORCEADD Q_CAP..1
(-3625 4375);
FORCEPROP 1 LAST LOCATION C1022
J 0
(-3575 4475);
DISPLAY 0.978723 (-3575 4475);
PAINT WHITE (-3575 4475);
FORCEPROP 0 LAST $SEC 1
J 0
(-3575 4525);
DISPLAY 0.680851 (-3575 4525);
PAINT MONO (-3575 4525);
DISPLAY INVISIBLE (-3575 4525);
FORCEPROP 0 LAST CDS_SEC 1
J 0
(-3575 4525);
DISPLAY 0.680851 (-3575 4525);
DISPLAY INVISIBLE (-3575 4525);
FORCEPROP 1 LASTPIN (-3625 4475) $PN 1
J 0
(-3615 4455);
DISPLAY 0.787234 (-3615 4455);
PAINT MONO (-3615 4455);
FORCEPROP 1 LASTPIN (-3625 4275) $PN 2
J 0
(-3615 4255);
DISPLAY 0.787234 (-3615 4255);
PAINT MONO (-3615 4255);
FORCEPROP 1 LAST TOLERANCE 20%
J 0
(-3575 4325);
DISPLAY 0.510638 (-3575 4325);
FORCEPROP 1 LAST MATERIAL X6S
J 0
(-3575 4275);
DISPLAY 0.510638 (-3575 4275);
FORCEPROP 1 LAST VALUE 100UF
J 0
(-3575 4425);
DISPLAY 0.510638 (-3575 4425);
FORCEPROP 1 LAST VOLTAGE 4V
J 0
(-3575 4375);
DISPLAY 0.510638 (-3575 4375);
FORCEPROP 1 LAST PACK_TYPE C0805
J 0
(-3575 4225);
DISPLAY 0.510638 (-3575 4225);
FORCEPROP 2 LAST CDS_LIB pure_quanta
J 0
(-3625 4375);
DISPLAY INVISIBLE (-3625 4375);
FORCEPROP 1 LAST PATH I66
J 0
(-3575 4525);
DISPLAY 0.978723 (-3575 4525);
PAINT WHITE (-3575 4525);
DISPLAY INVISIBLE (-3575 4525);
FORCEPROP 1 LAST PART_NUMBER CH710KMEA01
J 0
(-3575 4225);
DISPLAY 0.404255 (-3575 4225);
DISPLAY INVISIBLE (-3575 4225);
FORCEADD Q_CAP..1
(-3400 4375);
FORCEPROP 1 LAST LOCATION C1025
J 0
(-3350 4475);
DISPLAY 0.978723 (-3350 4475);
PAINT WHITE (-3350 4475);
FORCEPROP 0 LAST $SEC 1
J 0
(-3350 4525);
DISPLAY 0.680851 (-3350 4525);
PAINT MONO (-3350 4525);
DISPLAY INVISIBLE (-3350 4525);
FORCEPROP 0 LAST CDS_SEC 1
J 0
(-3350 4525);
DISPLAY 0.680851 (-3350 4525);
DISPLAY INVISIBLE (-3350 4525);
FORCEPROP 1 LASTPIN (-3400 4475) $PN 1
J 0
(-3390 4455);
DISPLAY 0.787234 (-3390 4455);
PAINT MONO (-3390 4455);
FORCEPROP 1 LASTPIN (-3400 4275) $PN 2
J 0
(-3390 4255);
DISPLAY 0.787234 (-3390 4255);
PAINT MONO (-3390 4255);
FORCEPROP 1 LAST VALUE 100UF
J 0
(-3350 4425);
DISPLAY 0.510638 (-3350 4425);
FORCEPROP 1 LAST TOLERANCE 20%
J 0
(-3350 4325);
DISPLAY 0.510638 (-3350 4325);
FORCEPROP 1 LAST VOLTAGE 4V
J 0
(-3350 4375);
DISPLAY 0.510638 (-3350 4375);
FORCEPROP 1 LAST MATERIAL X6S
J 0
(-3350 4275);
DISPLAY 0.510638 (-3350 4275);
FORCEPROP 1 LAST PACK_TYPE C0805
J 0
(-3350 4225);
DISPLAY 0.510638 (-3350 4225);
FORCEPROP 2 LAST CDS_LIB pure_quanta
J 0
(-3400 4375);
DISPLAY INVISIBLE (-3400 4375);
FORCEPROP 1 LAST PATH I67
J 0
(-3350 4525);
DISPLAY 0.978723 (-3350 4525);
PAINT WHITE (-3350 4525);
DISPLAY INVISIBLE (-3350 4525);
FORCEPROP 1 LAST PART_NUMBER CH710KMEA01
J 0
(-3350 4225);
DISPLAY 0.404255 (-3350 4225);
DISPLAY INVISIBLE (-3350 4225);
FORCEADD VCC_CORE..1
(-3625 5025);
FORCEPROP 3 LASTPIN (-3625 4975) SIG_NAME P0V9_CPU0_RT3_2A\g
J 0
(-3615 4985);
DISPLAY 0.659574 (-3615 4985);
PAINT MONO (-3615 4985);
DISPLAY INVISIBLE (-3615 4985);
FORCEPROP 1 LAST HDL_POWER P0V9_CPU0_RT3_2A
J 1
(-3625 5075);
DISPLAY 0.617021 (-3625 5075);
PAINT GREEN (-3625 5075);
FORCEPROP 2 LAST CDS_LIB pure_quanta_power
J 0
(-3625 5025);
DISPLAY INVISIBLE (-3625 5025);
FORCEPROP 1 LAST PATH I68
J 0
(-3575 5050);
DISPLAY 0.872340 (-3575 5050);
PAINT AQUA (-3575 5050);
DISPLAY INVISIBLE (-3575 5050);
FORCEADD Q_CAP..1
(-3575 5650);
FORCEPROP 1 LAST LOCATION C1028
J 0
(-3525 5750);
DISPLAY 0.978723 (-3525 5750);
PAINT WHITE (-3525 5750);
FORCEPROP 0 LAST $SEC 1
J 0
(-3525 5800);
DISPLAY 0.680851 (-3525 5800);
PAINT MONO (-3525 5800);
DISPLAY INVISIBLE (-3525 5800);
FORCEPROP 0 LAST CDS_SEC 1
J 0
(-3525 5800);
DISPLAY 0.680851 (-3525 5800);
DISPLAY INVISIBLE (-3525 5800);
FORCEPROP 1 LASTPIN (-3575 5750) $PN 1
J 0
(-3565 5730);
DISPLAY 0.787234 (-3565 5730);
PAINT MONO (-3565 5730);
FORCEPROP 1 LASTPIN (-3575 5550) $PN 2
J 0
(-3565 5530);
DISPLAY 0.787234 (-3565 5530);
PAINT MONO (-3565 5530);
FORCEPROP 1 LAST PACK_TYPE C0805
J 0
(-3525 5500);
DISPLAY 0.510638 (-3525 5500);
FORCEPROP 1 LAST TOLERANCE 20%
J 0
(-3525 5600);
DISPLAY 0.510638 (-3525 5600);
FORCEPROP 1 LAST MATERIAL X6S
J 0
(-3525 5550);
DISPLAY 0.510638 (-3525 5550);
FORCEPROP 1 LAST VOLTAGE 4V
J 0
(-3525 5650);
DISPLAY 0.510638 (-3525 5650);
FORCEPROP 1 LAST VALUE 100UF
J 0
(-3525 5700);
DISPLAY 0.510638 (-3525 5700);
FORCEPROP 2 LAST CDS_LIB pure_quanta
J 0
(-3575 5650);
DISPLAY INVISIBLE (-3575 5650);
FORCEPROP 1 LAST PATH I69
J 0
(-3525 5800);
DISPLAY 0.978723 (-3525 5800);
PAINT WHITE (-3525 5800);
DISPLAY INVISIBLE (-3525 5800);
FORCEPROP 1 LAST PART_NUMBER CH710KMEA01
J 0
(-3525 5500);
DISPLAY 0.404255 (-3525 5500);
DISPLAY INVISIBLE (-3525 5500);
FORCEADD Q_RES..2
R 2
(-4450 2950);
FORCEPROP 1 LAST LOCATION R1094
J 2
(-4495 3075);
DISPLAY 0.978723 (-4495 3075);
FORCEPROP 0 LAST $SEC 1
J 0
(-4475 3125);
DISPLAY 0.680851 (-4475 3125);
PAINT MONO (-4475 3125);
DISPLAY INVISIBLE (-4475 3125);
FORCEPROP 0 LAST CDS_SEC 1
J 0
(-4475 3125);
DISPLAY 0.680851 (-4475 3125);
DISPLAY INVISIBLE (-4475 3125);
FORCEPROP 1 LASTPIN (-4450 3050) $PN 1
J 2
(-4455 3012);
DISPLAY 0.787234 (-4455 3012);
PAINT MONO (-4455 3012);
FORCEPROP 1 LASTPIN (-4450 2850) $PN 2
J 2
(-4455 2860);
DISPLAY 0.787234 (-4455 2860);
PAINT MONO (-4455 2860);
FORCEPROP 1 LAST PACK_TYPE 0603LF
J 2
(-4490 2775);
DISPLAY 0.978723 (-4490 2775);
FORCEPROP 1 LAST TOLERANCE 5%
J 2
(-4495 2975);
DISPLAY 0.978723 (-4495 2975);
FORCEPROP 1 LAST WATTAGE 1/4W
J 2
(-4490 2925);
DISPLAY 0.978723 (-4490 2925);
FORCEPROP 1 LAST MATERIAL EMPTY
J 2
(-4490 2875);
DISPLAY 0.978723 (-4490 2875);
FORCEPROP 1 LAST VALUE 0
J 2
(-4495 3025);
DISPLAY 0.978723 (-4495 3025);
FORCEPROP 2 LAST CDS_LIB pure_quanta
J 2
(-4450 2950);
DISPLAY INVISIBLE (-4450 2950);
FORCEPROP 1 LAST PATH I7
J 2
(-4500 3125);
DISPLAY 0.978723 (-4500 3125);
PAINT WHITE (-4500 3125);
DISPLAY INVISIBLE (-4500 3125);
FORCEPROP 1 LAST PART_NUMBER CS00006J900
J 2
(-4490 2825);
DISPLAY 0.978723 (-4490 2825);
DISPLAY INVISIBLE (-4490 2825);
FORCEADD Q_CAP..1
(-3175 4375);
FORCEPROP 1 LAST LOCATION C1029
J 0
(-3125 4475);
DISPLAY 0.978723 (-3125 4475);
PAINT WHITE (-3125 4475);
FORCEPROP 0 LAST $SEC 1
J 0
(-3125 4525);
DISPLAY 0.680851 (-3125 4525);
PAINT MONO (-3125 4525);
DISPLAY INVISIBLE (-3125 4525);
FORCEPROP 0 LAST CDS_SEC 1
J 0
(-3125 4525);
DISPLAY 0.680851 (-3125 4525);
DISPLAY INVISIBLE (-3125 4525);
FORCEPROP 1 LASTPIN (-3175 4475) $PN 1
J 0
(-3165 4455);
DISPLAY 0.787234 (-3165 4455);
PAINT MONO (-3165 4455);
FORCEPROP 1 LASTPIN (-3175 4275) $PN 2
J 0
(-3165 4255);
DISPLAY 0.787234 (-3165 4255);
PAINT MONO (-3165 4255);
FORCEPROP 1 LAST TOLERANCE 20%
J 0
(-3125 4325);
DISPLAY 0.510638 (-3125 4325);
FORCEPROP 1 LAST PACK_TYPE C0805
J 0
(-3125 4225);
DISPLAY 0.510638 (-3125 4225);
FORCEPROP 1 LAST MATERIAL X6S
J 0
(-3125 4275);
DISPLAY 0.510638 (-3125 4275);
FORCEPROP 1 LAST VOLTAGE 4V
J 0
(-3125 4375);
DISPLAY 0.510638 (-3125 4375);
FORCEPROP 1 LAST VALUE 100UF
J 0
(-3125 4425);
DISPLAY 0.510638 (-3125 4425);
FORCEPROP 2 LAST CDS_LIB pure_quanta
J 0
(-3175 4375);
DISPLAY INVISIBLE (-3175 4375);
FORCEPROP 1 LAST PATH I70
J 0
(-3125 4525);
DISPLAY 0.978723 (-3125 4525);
PAINT WHITE (-3125 4525);
DISPLAY INVISIBLE (-3125 4525);
FORCEPROP 1 LAST PART_NUMBER CH710KMEA01
J 0
(-3125 4225);
DISPLAY 0.404255 (-3125 4225);
DISPLAY INVISIBLE (-3125 4225);
FORCEADD Q_CAP..1
(-2950 4375);
FORCEPROP 1 LAST LOCATION C1033
J 0
(-2900 4475);
DISPLAY 0.978723 (-2900 4475);
PAINT WHITE (-2900 4475);
FORCEPROP 0 LAST $SEC 1
J 0
(-2900 4525);
DISPLAY 0.680851 (-2900 4525);
PAINT MONO (-2900 4525);
DISPLAY INVISIBLE (-2900 4525);
FORCEPROP 0 LAST CDS_SEC 1
J 0
(-2900 4525);
DISPLAY 0.680851 (-2900 4525);
DISPLAY INVISIBLE (-2900 4525);
FORCEPROP 1 LASTPIN (-2950 4475) $PN 1
J 0
(-2940 4455);
DISPLAY 0.787234 (-2940 4455);
PAINT MONO (-2940 4455);
FORCEPROP 1 LASTPIN (-2950 4275) $PN 2
J 0
(-2940 4255);
DISPLAY 0.787234 (-2940 4255);
PAINT MONO (-2940 4255);
FORCEPROP 1 LAST PACK_TYPE C0805
J 0
(-2900 4225);
DISPLAY 0.510638 (-2900 4225);
FORCEPROP 1 LAST MATERIAL X6S
J 0
(-2900 4275);
DISPLAY 0.510638 (-2900 4275);
FORCEPROP 1 LAST TOLERANCE 20%
J 0
(-2900 4325);
DISPLAY 0.510638 (-2900 4325);
FORCEPROP 1 LAST VOLTAGE 4V
J 0
(-2900 4375);
DISPLAY 0.510638 (-2900 4375);
FORCEPROP 1 LAST VALUE 100UF
J 0
(-2900 4425);
DISPLAY 0.510638 (-2900 4425);
FORCEPROP 2 LAST CDS_LIB pure_quanta
J 0
(-2950 4375);
DISPLAY INVISIBLE (-2950 4375);
FORCEPROP 1 LAST PATH I71
J 0
(-2900 4525);
DISPLAY 0.978723 (-2900 4525);
PAINT WHITE (-2900 4525);
DISPLAY INVISIBLE (-2900 4525);
FORCEPROP 1 LAST PART_NUMBER CH710KMEA01
J 0
(-2900 4225);
DISPLAY 0.404255 (-2900 4225);
DISPLAY INVISIBLE (-2900 4225);
FORCEADD Q_CAP..1
(-2700 4375);
FORCEPROP 1 LAST LOCATION C1026
J 0
(-2650 4475);
DISPLAY 0.978723 (-2650 4475);
PAINT WHITE (-2650 4475);
FORCEPROP 0 LAST $SEC 1
J 0
(-2650 4525);
DISPLAY 0.680851 (-2650 4525);
PAINT MONO (-2650 4525);
DISPLAY INVISIBLE (-2650 4525);
FORCEPROP 0 LAST CDS_SEC 1
J 0
(-2650 4525);
DISPLAY 0.680851 (-2650 4525);
DISPLAY INVISIBLE (-2650 4525);
FORCEPROP 1 LASTPIN (-2700 4475) $PN 1
J 0
(-2690 4455);
DISPLAY 0.787234 (-2690 4455);
PAINT MONO (-2690 4455);
FORCEPROP 1 LASTPIN (-2700 4275) $PN 2
J 0
(-2690 4255);
DISPLAY 0.787234 (-2690 4255);
PAINT MONO (-2690 4255);
FORCEPROP 1 LAST VALUE 22UF
J 0
(-2650 4425);
DISPLAY 0.510638 (-2650 4425);
FORCEPROP 1 LAST VOLTAGE 4V
J 0
(-2650 4375);
DISPLAY 0.510638 (-2650 4375);
FORCEPROP 1 LAST TOLERANCE 20%
J 0
(-2650 4325);
DISPLAY 0.510638 (-2650 4325);
FORCEPROP 1 LAST MATERIAL X6S
J 0
(-2650 4275);
DISPLAY 0.510638 (-2650 4275);
FORCEPROP 1 LAST PACK_TYPE C0402
J 0
(-2650 4225);
DISPLAY 0.510638 (-2650 4225);
FORCEPROP 2 LAST CDS_LIB pure_quanta
J 0
(-2700 4375);
DISPLAY INVISIBLE (-2700 4375);
FORCEPROP 1 LAST PATH I72
J 0
(-2650 4525);
DISPLAY 0.978723 (-2650 4525);
PAINT WHITE (-2650 4525);
DISPLAY INVISIBLE (-2650 4525);
FORCEPROP 1 LAST PART_NUMBER CH622KMEB02
J 0
(-2650 4225);
DISPLAY 0.978723 (-2650 4225);
DISPLAY INVISIBLE (-2650 4225);
FORCEADD Q_CAP..1
(-2975 5625);
FORCEPROP 1 LAST LOCATION C1044
J 0
(-2925 5725);
DISPLAY 0.978723 (-2925 5725);
PAINT WHITE (-2925 5725);
FORCEPROP 0 LAST $SEC 1
J 0
(-2925 5775);
DISPLAY 0.680851 (-2925 5775);
PAINT MONO (-2925 5775);
DISPLAY INVISIBLE (-2925 5775);
FORCEPROP 0 LAST CDS_SEC 1
J 0
(-2925 5775);
DISPLAY 0.680851 (-2925 5775);
DISPLAY INVISIBLE (-2925 5775);
FORCEPROP 1 LASTPIN (-2975 5725) $PN 1
J 0
(-2965 5705);
DISPLAY 0.787234 (-2965 5705);
PAINT MONO (-2965 5705);
FORCEPROP 1 LASTPIN (-2975 5525) $PN 2
J 0
(-2965 5505);
DISPLAY 0.787234 (-2965 5505);
PAINT MONO (-2965 5505);
FORCEPROP 1 LAST TOLERANCE 20%
J 0
(-2925 5575);
DISPLAY 0.510638 (-2925 5575);
FORCEPROP 1 LAST MATERIAL X6S
J 0
(-2925 5525);
DISPLAY 0.510638 (-2925 5525);
FORCEPROP 1 LAST VOLTAGE 6.3V
J 0
(-2925 5625);
DISPLAY 0.510638 (-2925 5625);
FORCEPROP 1 LAST VALUE 10UF
J 0
(-2925 5675);
DISPLAY 0.510638 (-2925 5675);
FORCEPROP 1 LAST PACK_TYPE C0402
J 0
(-2925 5475);
DISPLAY 0.510638 (-2925 5475);
FORCEPROP 2 LAST CDS_LIB pure_quanta
J 0
(-2975 5625);
DISPLAY INVISIBLE (-2975 5625);
FORCEPROP 1 LAST PATH I73
J 0
(-2925 5775);
DISPLAY 0.978723 (-2925 5775);
PAINT WHITE (-2925 5775);
DISPLAY INVISIBLE (-2925 5775);
FORCEPROP 1 LAST PART_NUMBER CH6101MEB01
J 0
(-2925 5475);
DISPLAY 0.978723 (-2925 5475);
DISPLAY INVISIBLE (-2925 5475);
FORCEADD Q_CAP..1
(-3300 5650);
FORCEPROP 1 LAST LOCATION C1032
J 0
(-3250 5750);
DISPLAY 0.978723 (-3250 5750);
PAINT WHITE (-3250 5750);
FORCEPROP 0 LAST $SEC 1
J 0
(-3250 5800);
DISPLAY 0.680851 (-3250 5800);
PAINT MONO (-3250 5800);
DISPLAY INVISIBLE (-3250 5800);
FORCEPROP 0 LAST CDS_SEC 1
J 0
(-3250 5800);
DISPLAY 0.680851 (-3250 5800);
DISPLAY INVISIBLE (-3250 5800);
FORCEPROP 1 LASTPIN (-3300 5750) $PN 1
J 0
(-3290 5730);
DISPLAY 0.787234 (-3290 5730);
PAINT MONO (-3290 5730);
FORCEPROP 1 LASTPIN (-3300 5550) $PN 2
J 0
(-3290 5530);
DISPLAY 0.787234 (-3290 5530);
PAINT MONO (-3290 5530);
FORCEPROP 1 LAST MATERIAL X6S
J 0
(-3250 5550);
DISPLAY 0.510638 (-3250 5550);
FORCEPROP 1 LAST TOLERANCE 20%
J 0
(-3250 5600);
DISPLAY 0.510638 (-3250 5600);
FORCEPROP 1 LAST PACK_TYPE C0402
J 0
(-3250 5500);
DISPLAY 0.510638 (-3250 5500);
FORCEPROP 1 LAST VALUE 22UF
J 0
(-3250 5700);
DISPLAY 0.510638 (-3250 5700);
FORCEPROP 1 LAST VOLTAGE 4V
J 0
(-3250 5650);
DISPLAY 0.510638 (-3250 5650);
FORCEPROP 2 LAST CDS_LIB pure_quanta
J 0
(-3300 5650);
DISPLAY INVISIBLE (-3300 5650);
FORCEPROP 1 LAST PATH I74
J 0
(-3250 5800);
DISPLAY 0.978723 (-3250 5800);
PAINT WHITE (-3250 5800);
DISPLAY INVISIBLE (-3250 5800);
FORCEPROP 1 LAST PART_NUMBER CH622KMEB02
J 0
(-3250 5500);
DISPLAY 0.978723 (-3250 5500);
DISPLAY INVISIBLE (-3250 5500);
FORCEADD Q_CAP..1
(-2675 5625);
FORCEPROP 1 LAST LOCATION C1038
J 0
(-2625 5725);
DISPLAY 0.978723 (-2625 5725);
PAINT WHITE (-2625 5725);
FORCEPROP 0 LAST $SEC 1
J 0
(-2625 5775);
DISPLAY 0.680851 (-2625 5775);
PAINT MONO (-2625 5775);
DISPLAY INVISIBLE (-2625 5775);
FORCEPROP 0 LAST CDS_SEC 1
J 0
(-2625 5775);
DISPLAY 0.680851 (-2625 5775);
DISPLAY INVISIBLE (-2625 5775);
FORCEPROP 1 LASTPIN (-2675 5725) $PN 1
J 0
(-2665 5705);
DISPLAY 0.787234 (-2665 5705);
PAINT MONO (-2665 5705);
FORCEPROP 1 LASTPIN (-2675 5525) $PN 2
J 0
(-2665 5505);
DISPLAY 0.787234 (-2665 5505);
PAINT MONO (-2665 5505);
FORCEPROP 1 LAST PACK_TYPE 0402
J 0
(-2625 5475);
DISPLAY 0.510638 (-2625 5475);
FORCEPROP 1 LAST VALUE 4.7UF
J 0
(-2625 5675);
DISPLAY 0.510638 (-2625 5675);
FORCEPROP 1 LAST TOLERANCE 20%
J 0
(-2625 5575);
DISPLAY 0.510638 (-2625 5575);
FORCEPROP 1 LAST VOLTAGE 6.3V
J 0
(-2625 5625);
DISPLAY 0.510638 (-2625 5625);
FORCEPROP 1 LAST MATERIAL X6S
J 0
(-2625 5525);
DISPLAY 0.510638 (-2625 5525);
FORCEPROP 2 LAST CDS_LIB pure_quanta
J 0
(-2675 5625);
DISPLAY INVISIBLE (-2675 5625);
FORCEPROP 1 LAST PATH I75
J 0
(-2625 5775);
DISPLAY 0.978723 (-2625 5775);
PAINT WHITE (-2625 5775);
DISPLAY INVISIBLE (-2625 5775);
FORCEPROP 1 LAST PART_NUMBER CH5471MEB01
J 0
(-2625 5475);
DISPLAY 0.978723 (-2625 5475);
DISPLAY INVISIBLE (-2625 5475);
FORCEADD Q_CAP..1
(-2375 5625);
FORCEPROP 1 LAST LOCATION C1016
J 0
(-2325 5725);
DISPLAY 0.978723 (-2325 5725);
PAINT WHITE (-2325 5725);
FORCEPROP 0 LAST $SEC 1
J 0
(-2325 5775);
DISPLAY 0.680851 (-2325 5775);
PAINT MONO (-2325 5775);
DISPLAY INVISIBLE (-2325 5775);
FORCEPROP 0 LAST CDS_SEC 1
J 0
(-2325 5775);
DISPLAY 0.680851 (-2325 5775);
DISPLAY INVISIBLE (-2325 5775);
FORCEPROP 1 LASTPIN (-2375 5725) $PN 1
J 0
(-2365 5705);
DISPLAY 0.787234 (-2365 5705);
PAINT MONO (-2365 5705);
FORCEPROP 1 LASTPIN (-2375 5525) $PN 2
J 0
(-2365 5505);
DISPLAY 0.787234 (-2365 5505);
PAINT MONO (-2365 5505);
FORCEPROP 1 LAST PACK_TYPE 0201
J 0
(-2325 5475);
DISPLAY 0.510638 (-2325 5475);
FORCEPROP 1 LAST TOLERANCE 20%
J 0
(-2325 5575);
DISPLAY 0.510638 (-2325 5575);
FORCEPROP 1 LAST VOLTAGE 4V
J 0
(-2325 5625);
DISPLAY 0.510638 (-2325 5625);
FORCEPROP 1 LAST VALUE 1UF
J 0
(-2325 5675);
DISPLAY 0.510638 (-2325 5675);
FORCEPROP 1 LAST MATERIAL X6S
J 0
(-2325 5525);
DISPLAY 0.510638 (-2325 5525);
FORCEPROP 2 LAST CDS_LIB pure_quanta
J 0
(-2375 5625);
DISPLAY INVISIBLE (-2375 5625);
FORCEPROP 1 LAST PATH I76
J 0
(-2325 5775);
DISPLAY 0.978723 (-2325 5775);
PAINT WHITE (-2325 5775);
DISPLAY INVISIBLE (-2325 5775);
FORCEPROP 1 LAST PART_NUMBER CH-10KMEE00
J 0
(-2325 5475);
DISPLAY 0.510638 (-2325 5475);
DISPLAY INVISIBLE (-2325 5475);
FORCEADD Q_CAP..1
(-2250 4375);
FORCEPROP 1 LAST LOCATION C1030
J 0
(-2200 4475);
DISPLAY 0.978723 (-2200 4475);
PAINT WHITE (-2200 4475);
FORCEPROP 0 LAST $SEC 1
J 0
(-2200 4525);
DISPLAY 0.680851 (-2200 4525);
PAINT MONO (-2200 4525);
DISPLAY INVISIBLE (-2200 4525);
FORCEPROP 0 LAST CDS_SEC 1
J 0
(-2200 4525);
DISPLAY 0.680851 (-2200 4525);
DISPLAY INVISIBLE (-2200 4525);
FORCEPROP 1 LASTPIN (-2250 4475) $PN 1
J 0
(-2240 4455);
DISPLAY 0.787234 (-2240 4455);
PAINT MONO (-2240 4455);
FORCEPROP 1 LASTPIN (-2250 4275) $PN 2
J 0
(-2240 4255);
DISPLAY 0.787234 (-2240 4255);
PAINT MONO (-2240 4255);
FORCEPROP 1 LAST VALUE 22UF
J 0
(-2200 4425);
DISPLAY 0.510638 (-2200 4425);
FORCEPROP 1 LAST TOLERANCE 20%
J 0
(-2200 4325);
DISPLAY 0.510638 (-2200 4325);
FORCEPROP 1 LAST VOLTAGE 4V
J 0
(-2200 4375);
DISPLAY 0.510638 (-2200 4375);
FORCEPROP 1 LAST MATERIAL X6S
J 0
(-2200 4275);
DISPLAY 0.510638 (-2200 4275);
FORCEPROP 1 LAST PACK_TYPE C0402
J 0
(-2200 4225);
DISPLAY 0.510638 (-2200 4225);
FORCEPROP 2 LAST CDS_LIB pure_quanta
J 0
(-2250 4375);
DISPLAY INVISIBLE (-2250 4375);
FORCEPROP 1 LAST PATH I77
J 0
(-2200 4525);
DISPLAY 0.978723 (-2200 4525);
PAINT WHITE (-2200 4525);
DISPLAY INVISIBLE (-2200 4525);
FORCEPROP 1 LAST PART_NUMBER CH622KMEB02
J 0
(-2200 4225);
DISPLAY 0.978723 (-2200 4225);
DISPLAY INVISIBLE (-2200 4225);
FORCEADD Q_CAP..1
(-2025 4375);
FORCEPROP 1 LAST LOCATION C1041
J 0
(-1975 4475);
DISPLAY 0.978723 (-1975 4475);
PAINT WHITE (-1975 4475);
FORCEPROP 0 LAST $SEC 1
J 0
(-1975 4525);
DISPLAY 0.680851 (-1975 4525);
PAINT MONO (-1975 4525);
DISPLAY INVISIBLE (-1975 4525);
FORCEPROP 0 LAST CDS_SEC 1
J 0
(-1975 4525);
DISPLAY 0.680851 (-1975 4525);
DISPLAY INVISIBLE (-1975 4525);
FORCEPROP 1 LASTPIN (-2025 4475) $PN 1
J 0
(-2015 4455);
DISPLAY 0.787234 (-2015 4455);
PAINT MONO (-2015 4455);
FORCEPROP 1 LASTPIN (-2025 4275) $PN 2
J 0
(-2015 4255);
DISPLAY 0.787234 (-2015 4255);
PAINT MONO (-2015 4255);
FORCEPROP 1 LAST PACK_TYPE C0402
J 0
(-1975 4225);
DISPLAY 0.510638 (-1975 4225);
FORCEPROP 1 LAST TOLERANCE 20%
J 0
(-1975 4325);
DISPLAY 0.510638 (-1975 4325);
FORCEPROP 1 LAST VALUE 22UF
J 0
(-1975 4425);
DISPLAY 0.510638 (-1975 4425);
FORCEPROP 1 LAST VOLTAGE 4V
J 0
(-1975 4375);
DISPLAY 0.510638 (-1975 4375);
FORCEPROP 1 LAST MATERIAL X6S
J 0
(-1975 4275);
DISPLAY 0.510638 (-1975 4275);
FORCEPROP 2 LAST CDS_LIB pure_quanta
J 0
(-2025 4375);
DISPLAY INVISIBLE (-2025 4375);
FORCEPROP 1 LAST PATH I78
J 0
(-1975 4525);
DISPLAY 0.978723 (-1975 4525);
PAINT WHITE (-1975 4525);
DISPLAY INVISIBLE (-1975 4525);
FORCEPROP 1 LAST PART_NUMBER CH622KMEB02
J 0
(-1975 4225);
DISPLAY 0.978723 (-1975 4225);
DISPLAY INVISIBLE (-1975 4225);
FORCEADD Q_CAP..1
(-1725 4375);
FORCEPROP 1 LAST LOCATION C1037
J 0
(-1675 4475);
DISPLAY 0.978723 (-1675 4475);
PAINT WHITE (-1675 4475);
FORCEPROP 0 LAST $SEC 1
J 0
(-1675 4525);
DISPLAY 0.680851 (-1675 4525);
PAINT MONO (-1675 4525);
DISPLAY INVISIBLE (-1675 4525);
FORCEPROP 0 LAST CDS_SEC 1
J 0
(-1675 4525);
DISPLAY 0.680851 (-1675 4525);
DISPLAY INVISIBLE (-1675 4525);
FORCEPROP 1 LASTPIN (-1725 4475) $PN 1
J 0
(-1715 4455);
DISPLAY 0.787234 (-1715 4455);
PAINT MONO (-1715 4455);
FORCEPROP 1 LASTPIN (-1725 4275) $PN 2
J 0
(-1715 4255);
DISPLAY 0.787234 (-1715 4255);
PAINT MONO (-1715 4255);
FORCEPROP 1 LAST PACK_TYPE C0402
J 0
(-1675 4225);
DISPLAY 0.510638 (-1675 4225);
FORCEPROP 1 LAST MATERIAL X6S
J 0
(-1675 4275);
DISPLAY 0.510638 (-1675 4275);
FORCEPROP 1 LAST TOLERANCE 20%
J 0
(-1675 4325);
DISPLAY 0.510638 (-1675 4325);
FORCEPROP 1 LAST VOLTAGE 6.3V
J 0
(-1675 4375);
DISPLAY 0.510638 (-1675 4375);
FORCEPROP 1 LAST VALUE 10UF
J 0
(-1675 4425);
DISPLAY 0.510638 (-1675 4425);
FORCEPROP 2 LAST CDS_LIB pure_quanta
J 0
(-1725 4375);
DISPLAY INVISIBLE (-1725 4375);
FORCEPROP 1 LAST PATH I79
J 0
(-1675 4525);
DISPLAY 0.978723 (-1675 4525);
PAINT WHITE (-1675 4525);
DISPLAY INVISIBLE (-1675 4525);
FORCEPROP 1 LAST PART_NUMBER CH6101MEB01
J 0
(-1675 4225);
DISPLAY 0.978723 (-1675 4225);
DISPLAY INVISIBLE (-1675 4225);
FORCEADD Q_CAP..1
(-1425 4375);
FORCEPROP 1 LAST LOCATION C1049
J 0
(-1375 4475);
DISPLAY 0.978723 (-1375 4475);
PAINT WHITE (-1375 4475);
FORCEPROP 0 LAST $SEC 1
J 0
(-1375 4525);
DISPLAY 0.680851 (-1375 4525);
PAINT MONO (-1375 4525);
DISPLAY INVISIBLE (-1375 4525);
FORCEPROP 0 LAST CDS_SEC 1
J 0
(-1375 4525);
DISPLAY 0.680851 (-1375 4525);
DISPLAY INVISIBLE (-1375 4525);
FORCEPROP 1 LASTPIN (-1425 4475) $PN 1
J 0
(-1415 4455);
DISPLAY 0.787234 (-1415 4455);
PAINT MONO (-1415 4455);
FORCEPROP 1 LASTPIN (-1425 4275) $PN 2
J 0
(-1415 4255);
DISPLAY 0.787234 (-1415 4255);
PAINT MONO (-1415 4255);
FORCEPROP 1 LAST PACK_TYPE C0402
J 0
(-1375 4225);
DISPLAY 0.510638 (-1375 4225);
FORCEPROP 1 LAST VOLTAGE 6.3V
J 0
(-1375 4375);
DISPLAY 0.510638 (-1375 4375);
FORCEPROP 1 LAST MATERIAL X6S
J 0
(-1375 4275);
DISPLAY 0.510638 (-1375 4275);
FORCEPROP 1 LAST TOLERANCE 20%
J 0
(-1375 4325);
DISPLAY 0.510638 (-1375 4325);
FORCEPROP 1 LAST VALUE 10UF
J 0
(-1375 4425);
DISPLAY 0.510638 (-1375 4425);
FORCEPROP 2 LAST CDS_LIB pure_quanta
J 0
(-1425 4375);
DISPLAY INVISIBLE (-1425 4375);
FORCEPROP 1 LAST PATH I80
J 0
(-1375 4525);
DISPLAY 0.978723 (-1375 4525);
PAINT WHITE (-1375 4525);
DISPLAY INVISIBLE (-1375 4525);
FORCEPROP 1 LAST PART_NUMBER CH6101MEB01
J 0
(-1375 4225);
DISPLAY 0.978723 (-1375 4225);
DISPLAY INVISIBLE (-1375 4225);
FORCEADD Q_CAP..1
(-2075 5600);
FORCEPROP 1 LAST LOCATION C1007
J 0
(-2025 5700);
DISPLAY 0.978723 (-2025 5700);
PAINT WHITE (-2025 5700);
FORCEPROP 0 LAST $SEC 1
J 0
(-2025 5750);
DISPLAY 0.680851 (-2025 5750);
PAINT MONO (-2025 5750);
DISPLAY INVISIBLE (-2025 5750);
FORCEPROP 0 LAST CDS_SEC 1
J 0
(-2025 5750);
DISPLAY 0.680851 (-2025 5750);
DISPLAY INVISIBLE (-2025 5750);
FORCEPROP 1 LASTPIN (-2075 5700) $PN 1
J 0
(-2065 5680);
DISPLAY 0.787234 (-2065 5680);
PAINT MONO (-2065 5680);
FORCEPROP 1 LASTPIN (-2075 5500) $PN 2
J 0
(-2065 5480);
DISPLAY 0.787234 (-2065 5480);
PAINT MONO (-2065 5480);
FORCEPROP 1 LAST TOLERANCE 10%
J 0
(-2025 5550);
DISPLAY 0.638298 (-2025 5550);
FORCEPROP 1 LAST MATERIAL X7S
J 0
(-2025 5500);
DISPLAY 0.638298 (-2025 5500);
FORCEPROP 1 LAST VALUE 0.1UF
J 0
(-2025 5650);
DISPLAY 0.638298 (-2025 5650);
FORCEPROP 1 LAST VOLTAGE 10V
J 0
(-2025 5600);
DISPLAY 0.638298 (-2025 5600);
FORCEPROP 1 LAST PACK_TYPE C0201
J 0
(-2025 5450);
DISPLAY 0.638298 (-2025 5450);
FORCEPROP 2 LAST CDS_LIB pure_quanta
J 0
(-2075 5600);
DISPLAY INVISIBLE (-2075 5600);
FORCEPROP 1 LAST PATH I81
J 0
(-2025 5750);
DISPLAY 0.978723 (-2025 5750);
PAINT WHITE (-2025 5750);
DISPLAY INVISIBLE (-2025 5750);
FORCEPROP 1 LAST PART_NUMBER CH4102K6E00
J 0
(-2025 5450);
DISPLAY 0.978723 (-2025 5450);
DISPLAY INVISIBLE (-2025 5450);
FORCEADD Q_CAP..1
(-1800 5600);
FORCEPROP 1 LAST LOCATION C1009
J 0
(-1750 5700);
DISPLAY 0.978723 (-1750 5700);
PAINT WHITE (-1750 5700);
FORCEPROP 0 LAST $SEC 1
J 0
(-1750 5750);
DISPLAY 0.680851 (-1750 5750);
PAINT MONO (-1750 5750);
DISPLAY INVISIBLE (-1750 5750);
FORCEPROP 0 LAST CDS_SEC 1
J 0
(-1750 5750);
DISPLAY 0.680851 (-1750 5750);
DISPLAY INVISIBLE (-1750 5750);
FORCEPROP 1 LASTPIN (-1800 5700) $PN 1
J 0
(-1790 5680);
DISPLAY 0.787234 (-1790 5680);
PAINT MONO (-1790 5680);
FORCEPROP 1 LASTPIN (-1800 5500) $PN 2
J 0
(-1790 5480);
DISPLAY 0.787234 (-1790 5480);
PAINT MONO (-1790 5480);
FORCEPROP 1 LAST VALUE 0.1UF
J 0
(-1750 5650);
DISPLAY 0.638298 (-1750 5650);
FORCEPROP 1 LAST VOLTAGE 10V
J 0
(-1750 5600);
DISPLAY 0.638298 (-1750 5600);
FORCEPROP 1 LAST TOLERANCE 10%
J 0
(-1750 5550);
DISPLAY 0.638298 (-1750 5550);
FORCEPROP 1 LAST MATERIAL X7S
J 0
(-1750 5500);
DISPLAY 0.638298 (-1750 5500);
FORCEPROP 1 LAST PACK_TYPE C0201
J 0
(-1750 5450);
DISPLAY 0.638298 (-1750 5450);
FORCEPROP 2 LAST CDS_LIB pure_quanta
J 0
(-1800 5600);
DISPLAY INVISIBLE (-1800 5600);
FORCEPROP 1 LAST PATH I82
J 0
(-1750 5750);
DISPLAY 0.978723 (-1750 5750);
PAINT WHITE (-1750 5750);
DISPLAY INVISIBLE (-1750 5750);
FORCEPROP 1 LAST PART_NUMBER CH4102K6E00
J 0
(-1750 5450);
DISPLAY 0.978723 (-1750 5450);
DISPLAY INVISIBLE (-1750 5450);
FORCEADD UNIVERSAL_GND..1
(-1350 5200);
FORCEPROP 3 LASTPIN (-1350 5250) SIG_NAME GND\g
J 0
(-1340 5260);
DISPLAY 0.659574 (-1340 5260);
PAINT MONO (-1340 5260);
DISPLAY INVISIBLE (-1340 5260);
FORCEPROP 2 LAST CDS_LIB pure_quanta_power
J 0
(-1350 5200);
DISPLAY INVISIBLE (-1350 5200);
FORCEPROP 1 LAST HDL_POWER GND
J 1
(-1325 5125);
DISPLAY 0.872340 (-1325 5125);
PAINT GREEN (-1325 5125);
DISPLAY INVISIBLE (-1325 5125);
FORCEPROP 1 LAST PATH I83
J 0
(-1275 5200);
DISPLAY 0.872340 (-1275 5200);
PAINT AQUA (-1275 5200);
DISPLAY INVISIBLE (-1275 5200);
FORCEADD Q_CAP..1
(-1550 5600);
FORCEPROP 1 LAST LOCATION C1012
J 0
(-1500 5700);
DISPLAY 0.978723 (-1500 5700);
PAINT WHITE (-1500 5700);
FORCEPROP 0 LAST $SEC 1
J 0
(-1500 5750);
DISPLAY 0.680851 (-1500 5750);
PAINT MONO (-1500 5750);
DISPLAY INVISIBLE (-1500 5750);
FORCEPROP 0 LAST CDS_SEC 1
J 0
(-1500 5750);
DISPLAY 0.680851 (-1500 5750);
DISPLAY INVISIBLE (-1500 5750);
FORCEPROP 1 LASTPIN (-1550 5700) $PN 1
J 0
(-1540 5680);
DISPLAY 0.787234 (-1540 5680);
PAINT MONO (-1540 5680);
FORCEPROP 1 LASTPIN (-1550 5500) $PN 2
J 0
(-1540 5480);
DISPLAY 0.787234 (-1540 5480);
PAINT MONO (-1540 5480);
FORCEPROP 1 LAST VALUE 0.1UF
J 0
(-1500 5650);
DISPLAY 0.638298 (-1500 5650);
FORCEPROP 1 LAST MATERIAL X7S
J 0
(-1500 5500);
DISPLAY 0.638298 (-1500 5500);
FORCEPROP 1 LAST PACK_TYPE C0201
J 0
(-1500 5450);
DISPLAY 0.638298 (-1500 5450);
FORCEPROP 1 LAST VOLTAGE 10V
J 0
(-1500 5600);
DISPLAY 0.638298 (-1500 5600);
FORCEPROP 1 LAST TOLERANCE 10%
J 0
(-1500 5550);
DISPLAY 0.638298 (-1500 5550);
FORCEPROP 2 LAST CDS_LIB pure_quanta
J 0
(-1550 5600);
DISPLAY INVISIBLE (-1550 5600);
FORCEPROP 1 LAST PATH I84
J 0
(-1500 5750);
DISPLAY 0.978723 (-1500 5750);
PAINT WHITE (-1500 5750);
DISPLAY INVISIBLE (-1500 5750);
FORCEPROP 1 LAST PART_NUMBER CH4102K6E00
J 0
(-1500 5450);
DISPLAY 0.978723 (-1500 5450);
DISPLAY INVISIBLE (-1500 5450);
FORCEADD Q_CAP..1
(-1275 5600);
FORCEPROP 1 LAST LOCATION C1048
J 0
(-1225 5700);
DISPLAY 0.978723 (-1225 5700);
PAINT WHITE (-1225 5700);
FORCEPROP 0 LAST $SEC 1
J 0
(-1225 5750);
DISPLAY 0.680851 (-1225 5750);
PAINT MONO (-1225 5750);
DISPLAY INVISIBLE (-1225 5750);
FORCEPROP 0 LAST CDS_SEC 1
J 0
(-1225 5750);
DISPLAY 0.680851 (-1225 5750);
DISPLAY INVISIBLE (-1225 5750);
FORCEPROP 1 LASTPIN (-1275 5700) $PN 1
J 0
(-1265 5680);
DISPLAY 0.787234 (-1265 5680);
PAINT MONO (-1265 5680);
FORCEPROP 1 LASTPIN (-1275 5500) $PN 2
J 0
(-1265 5480);
DISPLAY 0.787234 (-1265 5480);
PAINT MONO (-1265 5480);
FORCEPROP 1 LAST VOLTAGE 10V
J 0
(-1225 5600);
DISPLAY 0.638298 (-1225 5600);
FORCEPROP 1 LAST TOLERANCE 10%
J 0
(-1225 5550);
DISPLAY 0.638298 (-1225 5550);
FORCEPROP 1 LAST MATERIAL X7S
J 0
(-1225 5500);
DISPLAY 0.638298 (-1225 5500);
FORCEPROP 1 LAST PACK_TYPE C0201
J 0
(-1225 5450);
DISPLAY 0.638298 (-1225 5450);
FORCEPROP 1 LAST VALUE 0.1UF
J 0
(-1225 5650);
DISPLAY 0.638298 (-1225 5650);
FORCEPROP 2 LAST CDS_LIB pure_quanta
J 0
(-1275 5600);
DISPLAY INVISIBLE (-1275 5600);
FORCEPROP 1 LAST PATH I85
J 0
(-1225 5750);
DISPLAY 0.978723 (-1225 5750);
PAINT WHITE (-1225 5750);
DISPLAY INVISIBLE (-1225 5750);
FORCEPROP 1 LAST PART_NUMBER CH4102K6E00
J 0
(-1225 5450);
DISPLAY 0.978723 (-1225 5450);
DISPLAY INVISIBLE (-1225 5450);
FORCEADD Q_CAP..1
(-2475 4375);
FORCEPROP 1 LAST LOCATION C1040
J 0
(-2425 4475);
DISPLAY 0.978723 (-2425 4475);
PAINT WHITE (-2425 4475);
FORCEPROP 0 LAST $SEC 1
J 0
(-2425 4525);
DISPLAY 0.680851 (-2425 4525);
PAINT MONO (-2425 4525);
DISPLAY INVISIBLE (-2425 4525);
FORCEPROP 0 LAST CDS_SEC 1
J 0
(-2425 4525);
DISPLAY 0.680851 (-2425 4525);
DISPLAY INVISIBLE (-2425 4525);
FORCEPROP 1 LASTPIN (-2475 4475) $PN 1
J 0
(-2465 4455);
DISPLAY 0.787234 (-2465 4455);
PAINT MONO (-2465 4455);
FORCEPROP 1 LASTPIN (-2475 4275) $PN 2
J 0
(-2465 4255);
DISPLAY 0.787234 (-2465 4255);
PAINT MONO (-2465 4255);
FORCEPROP 1 LAST PACK_TYPE C0402
J 0
(-2425 4225);
DISPLAY 0.510638 (-2425 4225);
FORCEPROP 1 LAST VALUE 22UF
J 0
(-2425 4425);
DISPLAY 0.510638 (-2425 4425);
FORCEPROP 1 LAST TOLERANCE 20%
J 0
(-2425 4325);
DISPLAY 0.510638 (-2425 4325);
FORCEPROP 1 LAST VOLTAGE 4V
J 0
(-2425 4375);
DISPLAY 0.510638 (-2425 4375);
FORCEPROP 1 LAST MATERIAL X6S
J 0
(-2425 4275);
DISPLAY 0.510638 (-2425 4275);
FORCEPROP 2 LAST CDS_LIB pure_quanta
J 0
(-2475 4375);
DISPLAY INVISIBLE (-2475 4375);
FORCEPROP 1 LAST PATH I86
J 0
(-2425 4525);
DISPLAY 0.978723 (-2425 4525);
PAINT WHITE (-2425 4525);
DISPLAY INVISIBLE (-2425 4525);
FORCEPROP 1 LAST PART_NUMBER CH622KMEB02
J 0
(-2425 4225);
DISPLAY 0.978723 (-2425 4225);
DISPLAY INVISIBLE (-2425 4225);
FORCEADD Q_CAP..1
(-3175 3750);
FORCEPROP 1 LAST LOCATION C1045
J 0
(-3125 3850);
DISPLAY 0.978723 (-3125 3850);
PAINT WHITE (-3125 3850);
FORCEPROP 0 LAST $SEC 1
J 0
(-3125 3900);
DISPLAY 0.680851 (-3125 3900);
PAINT MONO (-3125 3900);
DISPLAY INVISIBLE (-3125 3900);
FORCEPROP 0 LAST CDS_SEC 1
J 0
(-3125 3900);
DISPLAY 0.680851 (-3125 3900);
DISPLAY INVISIBLE (-3125 3900);
FORCEPROP 1 LASTPIN (-3175 3850) $PN 1
J 0
(-3165 3830);
DISPLAY 0.787234 (-3165 3830);
PAINT MONO (-3165 3830);
FORCEPROP 1 LASTPIN (-3175 3650) $PN 2
J 0
(-3165 3630);
DISPLAY 0.787234 (-3165 3630);
PAINT MONO (-3165 3630);
FORCEPROP 1 LAST VALUE 4.7UF
J 0
(-3125 3800);
DISPLAY 0.510638 (-3125 3800);
FORCEPROP 1 LAST MATERIAL X6S
J 0
(-3125 3650);
DISPLAY 0.510638 (-3125 3650);
FORCEPROP 1 LAST TOLERANCE 20%
J 0
(-3125 3700);
DISPLAY 0.510638 (-3125 3700);
FORCEPROP 1 LAST VOLTAGE 6.3V
J 0
(-3125 3750);
DISPLAY 0.510638 (-3125 3750);
FORCEPROP 1 LAST PACK_TYPE 0402
J 0
(-3125 3600);
DISPLAY 0.510638 (-3125 3600);
FORCEPROP 2 LAST CDS_LIB pure_quanta
J 0
(-3175 3750);
DISPLAY INVISIBLE (-3175 3750);
FORCEPROP 1 LAST PATH I87
J 0
(-3125 3900);
DISPLAY 0.978723 (-3125 3900);
PAINT WHITE (-3125 3900);
DISPLAY INVISIBLE (-3125 3900);
FORCEPROP 1 LAST PART_NUMBER CH5471MEB01
J 0
(-3125 3600);
DISPLAY 0.978723 (-3125 3600);
DISPLAY INVISIBLE (-3125 3600);
FORCEADD Q_INDUCTOR..1
R 3
(-8375 4300);
FORCEPROP 1 LAST LOCATION L30
R 1
J 2
(-8535 4425);
DISPLAY 0.723404 (-8535 4425);
PAINT GREEN (-8535 4425);
FORCEPROP 0 LAST $SEC 1
R 1
J 0
(-8350 4425);
DISPLAY 0.680851 (-8350 4425);
PAINT MONO (-8350 4425);
DISPLAY INVISIBLE (-8350 4425);
FORCEPROP 0 LAST CDS_SEC 1
R 1
J 0
(-8350 4425);
DISPLAY 0.680851 (-8350 4425);
DISPLAY INVISIBLE (-8350 4425);
FORCEPROP 0 LASTPIN (-8350 4400) $PN 1
R 1
J 0
(-8360 4410);
DISPLAY 0.680851 (-8360 4410);
PAINT MONO (-8360 4410);
FORCEPROP 0 LASTPIN (-8350 4200) $PN 2
R 1
J 2
(-8360 4190);
DISPLAY 0.680851 (-8360 4190);
PAINT MONO (-8360 4190);
FORCEPROP 2 LAST VALUE BLM15PD121SN1D/1300MA
R 1
J 2
(-8625 4425);
DISPLAY 0.553191 (-8625 4425);
FORCEPROP 2 LAST PACK_TYPE SMLF
R 1
J 2
(-8575 4425);
DISPLAY 0.553191 (-8575 4425);
FORCEPROP 1 LAST MATERIAL IND
R 1
J 2
(-8430 4425);
DISPLAY 0.574468 (-8430 4425);
PAINT GREEN (-8430 4425);
FORCEPROP 2 LAST CDS_LIB pure_quanta
J 0
(-8375 4300);
DISPLAY INVISIBLE (-8375 4300);
FORCEPROP 1 LAST NEEDS_NO_SIZE TRUE
R 1
J 2
(-8375 4300);
DISPLAY 0.468085 (-8375 4300);
PAINT GREEN (-8375 4300);
DISPLAY INVISIBLE (-8375 4300);
FORCEPROP 1 LAST PATH I88
R 1
J 2
(-8430 4225);
DISPLAY 0.723404 (-8430 4225);
PAINT GREEN (-8430 4225);
DISPLAY INVISIBLE (-8430 4225);
FORCEPROP 1 LAST PART_NUMBER CX5PD121000
R 1
J 2
(-8475 4425);
DISPLAY 0.574468 (-8475 4425);
PAINT GREEN (-8475 4425);
DISPLAY INVISIBLE (-8475 4425);
FORCEADD Q_RES..2
(-8250 4275);
FORCEPROP 1 LAST LOCATION R1093
J 0
(-8205 4400);
DISPLAY 0.808511 (-8205 4400);
FORCEPROP 0 LAST $SEC 1
J 0
(-8200 4450);
DISPLAY 0.680851 (-8200 4450);
PAINT MONO (-8200 4450);
DISPLAY INVISIBLE (-8200 4450);
FORCEPROP 0 LAST CDS_SEC 1
J 0
(-8200 4450);
DISPLAY 0.680851 (-8200 4450);
DISPLAY INVISIBLE (-8200 4450);
FORCEPROP 1 LASTPIN (-8250 4375) $PN 1
J 0
(-8245 4337);
DISPLAY 0.787234 (-8245 4337);
PAINT MONO (-8245 4337);
FORCEPROP 1 LASTPIN (-8250 4175) $PN 2
J 0
(-8245 4185);
DISPLAY 0.787234 (-8245 4185);
PAINT MONO (-8245 4185);
FORCEPROP 1 LAST WATTAGE 1/16W
J 0
(-8210 4250);
DISPLAY 0.638298 (-8210 4250);
FORCEPROP 1 LAST MATERIAL EMPTY
J 0
(-8210 4200);
DISPLAY 0.638298 (-8210 4200);
PAINT RED (-8210 4200);
FORCEPROP 1 LAST PACK_TYPE 0402LF
J 0
(-8210 4100);
DISPLAY 0.638298 (-8210 4100);
FORCEPROP 1 LAST TOLERANCE 5%
J 0
(-8205 4300);
DISPLAY 0.638298 (-8205 4300);
FORCEPROP 1 LAST VALUE 0
J 0
(-8205 4350);
DISPLAY 0.638298 (-8205 4350);
FORCEPROP 2 LAST CDS_LIB pure_quanta
J 0
(-8250 4275);
DISPLAY INVISIBLE (-8250 4275);
FORCEPROP 1 LAST PATH I89
J 0
(-8200 4450);
DISPLAY 0.978723 (-8200 4450);
PAINT WHITE (-8200 4450);
DISPLAY INVISIBLE (-8200 4450);
FORCEPROP 1 LAST PART_NUMBER CS00002JB13
J 0
(-8210 4150);
DISPLAY 0.638298 (-8210 4150);
DISPLAY INVISIBLE (-8210 4150);
FORCEADD Q_CAP..1
(-2925 1325);
FORCEPROP 1 LAST LOCATION C1018
J 0
(-2875 1425);
DISPLAY 0.978723 (-2875 1425);
PAINT WHITE (-2875 1425);
FORCEPROP 0 LAST $SEC 1
J 0
(-2875 1475);
DISPLAY 0.680851 (-2875 1475);
PAINT MONO (-2875 1475);
DISPLAY INVISIBLE (-2875 1475);
FORCEPROP 0 LAST CDS_SEC 1
J 0
(-2875 1475);
DISPLAY 0.680851 (-2875 1475);
DISPLAY INVISIBLE (-2875 1475);
FORCEPROP 1 LASTPIN (-2925 1425) $PN 1
J 0
(-2915 1405);
DISPLAY 0.787234 (-2915 1405);
PAINT MONO (-2915 1405);
FORCEPROP 1 LASTPIN (-2925 1225) $PN 2
J 0
(-2915 1205);
DISPLAY 0.787234 (-2915 1205);
PAINT MONO (-2915 1205);
FORCEPROP 1 LAST PACK_TYPE 0201
J 0
(-2875 1175);
DISPLAY 0.510638 (-2875 1175);
FORCEPROP 1 LAST MATERIAL X6S
J 0
(-2875 1225);
DISPLAY 0.510638 (-2875 1225);
FORCEPROP 1 LAST TOLERANCE 20%
J 0
(-2875 1275);
DISPLAY 0.510638 (-2875 1275);
FORCEPROP 1 LAST VOLTAGE 4V
J 0
(-2875 1325);
DISPLAY 0.510638 (-2875 1325);
FORCEPROP 1 LAST VALUE 1UF
J 0
(-2875 1375);
DISPLAY 0.510638 (-2875 1375);
FORCEPROP 2 LAST CDS_LIB pure_quanta
J 0
(-2925 1325);
DISPLAY INVISIBLE (-2925 1325);
FORCEPROP 1 LAST PATH I90
J 0
(-2875 1475);
DISPLAY 0.978723 (-2875 1475);
PAINT WHITE (-2875 1475);
DISPLAY INVISIBLE (-2875 1475);
FORCEPROP 1 LAST PART_NUMBER CH-10KMEE00
J 0
(-2875 1175);
DISPLAY 0.510638 (-2875 1175);
DISPLAY INVISIBLE (-2875 1175);
FORCEADD Q_CAP..1
(-2625 1325);
FORCEPROP 1 LAST LOCATION C1020
J 0
(-2575 1425);
DISPLAY 0.978723 (-2575 1425);
PAINT WHITE (-2575 1425);
FORCEPROP 0 LAST $SEC 1
J 0
(-2575 1475);
DISPLAY 0.680851 (-2575 1475);
PAINT MONO (-2575 1475);
DISPLAY INVISIBLE (-2575 1475);
FORCEPROP 0 LAST CDS_SEC 1
J 0
(-2575 1475);
DISPLAY 0.680851 (-2575 1475);
DISPLAY INVISIBLE (-2575 1475);
FORCEPROP 1 LASTPIN (-2625 1425) $PN 1
J 0
(-2615 1405);
DISPLAY 0.787234 (-2615 1405);
PAINT MONO (-2615 1405);
FORCEPROP 1 LASTPIN (-2625 1225) $PN 2
J 0
(-2615 1205);
DISPLAY 0.787234 (-2615 1205);
PAINT MONO (-2615 1205);
FORCEPROP 1 LAST VOLTAGE 4V
J 0
(-2575 1325);
DISPLAY 0.510638 (-2575 1325);
FORCEPROP 1 LAST VALUE 1UF
J 0
(-2575 1375);
DISPLAY 0.510638 (-2575 1375);
FORCEPROP 1 LAST MATERIAL X6S
J 0
(-2575 1225);
DISPLAY 0.510638 (-2575 1225);
FORCEPROP 1 LAST PACK_TYPE 0201
J 0
(-2575 1175);
DISPLAY 0.510638 (-2575 1175);
FORCEPROP 1 LAST TOLERANCE 20%
J 0
(-2575 1275);
DISPLAY 0.510638 (-2575 1275);
FORCEPROP 2 LAST CDS_LIB pure_quanta
J 0
(-2625 1325);
DISPLAY INVISIBLE (-2625 1325);
FORCEPROP 1 LAST PATH I91
J 0
(-2575 1475);
DISPLAY 0.978723 (-2575 1475);
PAINT WHITE (-2575 1475);
DISPLAY INVISIBLE (-2575 1475);
FORCEPROP 1 LAST PART_NUMBER CH-10KMEE00
J 0
(-2575 1175);
DISPLAY 0.510638 (-2575 1175);
DISPLAY INVISIBLE (-2575 1175);
FORCEADD Q_CAP..1
(-2000 3100);
FORCEPROP 1 LAST LOCATION C1051
J 0
(-1950 3200);
DISPLAY 0.978723 (-1950 3200);
PAINT WHITE (-1950 3200);
FORCEPROP 0 LAST $SEC 1
J 0
(-1950 3250);
DISPLAY 0.680851 (-1950 3250);
PAINT MONO (-1950 3250);
DISPLAY INVISIBLE (-1950 3250);
FORCEPROP 0 LAST CDS_SEC 1
J 0
(-1950 3250);
DISPLAY 0.680851 (-1950 3250);
DISPLAY INVISIBLE (-1950 3250);
FORCEPROP 1 LASTPIN (-2000 3200) $PN 1
J 0
(-1990 3180);
DISPLAY 0.787234 (-1990 3180);
PAINT MONO (-1990 3180);
FORCEPROP 1 LASTPIN (-2000 3000) $PN 2
J 0
(-1990 2980);
DISPLAY 0.787234 (-1990 2980);
PAINT MONO (-1990 2980);
FORCEPROP 1 LAST TOLERANCE 10%
J 0
(-1950 3050);
DISPLAY 0.638298 (-1950 3050);
FORCEPROP 1 LAST VOLTAGE 10V
J 0
(-1950 3100);
DISPLAY 0.638298 (-1950 3100);
FORCEPROP 1 LAST MATERIAL X7S
J 0
(-1950 3000);
DISPLAY 0.638298 (-1950 3000);
FORCEPROP 1 LAST VALUE 0.1UF
J 0
(-1950 3150);
DISPLAY 0.638298 (-1950 3150);
FORCEPROP 1 LAST PACK_TYPE C0201
J 0
(-1950 2950);
DISPLAY 0.638298 (-1950 2950);
FORCEPROP 2 LAST CDS_LIB pure_quanta
J 0
(-2000 3100);
DISPLAY INVISIBLE (-2000 3100);
FORCEPROP 1 LAST PATH I92
J 0
(-1950 3250);
DISPLAY 0.978723 (-1950 3250);
PAINT WHITE (-1950 3250);
DISPLAY INVISIBLE (-1950 3250);
FORCEPROP 1 LAST PART_NUMBER CH4102K6E00
J 0
(-1950 2950);
DISPLAY 0.978723 (-1950 2950);
DISPLAY INVISIBLE (-1950 2950);
FORCEADD Q_CAP..1
(-1750 3100);
FORCEPROP 1 LAST LOCATION C1053
J 0
(-1700 3200);
DISPLAY 0.978723 (-1700 3200);
PAINT WHITE (-1700 3200);
FORCEPROP 0 LAST $SEC 1
J 0
(-1700 3250);
DISPLAY 0.680851 (-1700 3250);
PAINT MONO (-1700 3250);
DISPLAY INVISIBLE (-1700 3250);
FORCEPROP 0 LAST CDS_SEC 1
J 0
(-1700 3250);
DISPLAY 0.680851 (-1700 3250);
DISPLAY INVISIBLE (-1700 3250);
FORCEPROP 1 LASTPIN (-1750 3200) $PN 1
J 0
(-1740 3180);
DISPLAY 0.787234 (-1740 3180);
PAINT MONO (-1740 3180);
FORCEPROP 1 LASTPIN (-1750 3000) $PN 2
J 0
(-1740 2980);
DISPLAY 0.787234 (-1740 2980);
PAINT MONO (-1740 2980);
FORCEPROP 1 LAST VOLTAGE 10V
J 0
(-1700 3100);
DISPLAY 0.638298 (-1700 3100);
FORCEPROP 1 LAST VALUE 0.1UF
J 0
(-1700 3150);
DISPLAY 0.638298 (-1700 3150);
FORCEPROP 1 LAST TOLERANCE 10%
J 0
(-1700 3050);
DISPLAY 0.638298 (-1700 3050);
FORCEPROP 1 LAST MATERIAL X7S
J 0
(-1700 3000);
DISPLAY 0.638298 (-1700 3000);
FORCEPROP 1 LAST PACK_TYPE C0201
J 0
(-1700 2950);
DISPLAY 0.638298 (-1700 2950);
FORCEPROP 2 LAST CDS_LIB pure_quanta
J 0
(-1750 3100);
DISPLAY INVISIBLE (-1750 3100);
FORCEPROP 1 LAST PATH I93
J 0
(-1700 3250);
DISPLAY 0.978723 (-1700 3250);
PAINT WHITE (-1700 3250);
DISPLAY INVISIBLE (-1700 3250);
FORCEPROP 1 LAST PART_NUMBER CH4102K6E00
J 0
(-1700 2950);
DISPLAY 0.978723 (-1700 2950);
DISPLAY INVISIBLE (-1700 2950);
FORCEADD Q_CAPP..1
(-1200 2450);
FORCEPROP 1 LAST LOCATION C7017
J 0
(-1150 2550);
DISPLAY 0.787234 (-1150 2550);
FORCEPROP 0 LAST $SEC 1
J 0
(-1150 2600);
DISPLAY 0.680851 (-1150 2600);
PAINT MONO (-1150 2600);
DISPLAY INVISIBLE (-1150 2600);
FORCEPROP 0 LAST CDS_SEC 1
J 0
(-1150 2600);
DISPLAY 0.680851 (-1150 2600);
DISPLAY INVISIBLE (-1150 2600);
FORCEPROP 1 LASTPIN (-1200 2550) $PN 1
J 0
(-1190 2535);
DISPLAY 0.787234 (-1190 2535);
PAINT MONO (-1190 2535);
FORCEPROP 1 LASTPIN (-1200 2350) $PN 2
J 0
(-1190 2335);
DISPLAY 0.787234 (-1190 2335);
PAINT MONO (-1190 2335);
FORCEPROP 1 LAST VALUE 470UF
J 0
(-1150 2500);
DISPLAY 0.510638 (-1150 2500);
FORCEPROP 1 LAST TOLERANCE 20%
J 0
(-1150 2450);
DISPLAY 0.510638 (-1150 2450);
FORCEPROP 1 LAST PACK_TYPE SMLF
J 0
(-1150 2300);
DISPLAY 0.510638 (-1150 2300);
FORCEPROP 1 LAST VOLTAGE 2.5V
J 0
(-1150 2400);
DISPLAY 0.510638 (-1150 2400);
FORCEPROP 1 LAST MATERIAL SPCAP
J 0
(-1150 2350);
DISPLAY 0.510638 (-1150 2350);
FORCEPROP 2 LAST CDS_LIB pure_quanta
J 0
(-1200 2450);
DISPLAY INVISIBLE (-1200 2450);
FORCEPROP 1 LAST PATH I94
J 0
(-1150 2600);
DISPLAY 0.978723 (-1150 2600);
DISPLAY INVISIBLE (-1150 2600);
FORCEPROP 1 LAST PART_NUMBER CH747LM8818
J 0
(-1150 2250);
DISPLAY 0.404255 (-1150 2250);
DISPLAY INVISIBLE (-1150 2250);
FORCEADD Q_CAPP..1
(-900 2450);
FORCEPROP 1 LAST LOCATION C7018
J 0
(-850 2550);
DISPLAY 0.787234 (-850 2550);
FORCEPROP 0 LAST $SEC 1
J 0
(-850 2600);
DISPLAY 0.680851 (-850 2600);
PAINT MONO (-850 2600);
DISPLAY INVISIBLE (-850 2600);
FORCEPROP 0 LAST CDS_SEC 1
J 0
(-850 2600);
DISPLAY 0.680851 (-850 2600);
DISPLAY INVISIBLE (-850 2600);
FORCEPROP 1 LASTPIN (-900 2550) $PN 1
J 0
(-890 2535);
DISPLAY 0.787234 (-890 2535);
PAINT MONO (-890 2535);
FORCEPROP 1 LASTPIN (-900 2350) $PN 2
J 0
(-890 2335);
DISPLAY 0.787234 (-890 2335);
PAINT MONO (-890 2335);
FORCEPROP 1 LAST VOLTAGE 2.5V
J 0
(-850 2400);
DISPLAY 0.510638 (-850 2400);
FORCEPROP 1 LAST PACK_TYPE SMLF
J 0
(-850 2300);
DISPLAY 0.510638 (-850 2300);
FORCEPROP 1 LAST MATERIAL SPCAP
J 0
(-850 2350);
DISPLAY 0.510638 (-850 2350);
FORCEPROP 1 LAST TOLERANCE 20%
J 0
(-850 2450);
DISPLAY 0.510638 (-850 2450);
FORCEPROP 1 LAST VALUE 470UF
J 0
(-850 2500);
DISPLAY 0.510638 (-850 2500);
FORCEPROP 2 LAST CDS_LIB pure_quanta
J 0
(-900 2450);
DISPLAY INVISIBLE (-900 2450);
FORCEPROP 1 LAST PATH I95
J 0
(-850 2600);
DISPLAY 0.978723 (-850 2600);
DISPLAY INVISIBLE (-850 2600);
FORCEPROP 1 LAST PART_NUMBER CH747LM8818
J 0
(-850 2250);
DISPLAY 0.404255 (-850 2250);
DISPLAY INVISIBLE (-850 2250);
FORCEADD Q_CAP..1
(-600 2450);
FORCEPROP 1 LAST LOCATION C7019
J 0
(-550 2550);
DISPLAY 0.638298 (-550 2550);
FORCEPROP 0 LAST $SEC 1
J 0
(-550 2600);
DISPLAY 0.680851 (-550 2600);
PAINT MONO (-550 2600);
DISPLAY INVISIBLE (-550 2600);
FORCEPROP 0 LAST CDS_SEC 1
J 0
(-550 2600);
DISPLAY 0.680851 (-550 2600);
DISPLAY INVISIBLE (-550 2600);
FORCEPROP 1 LASTPIN (-600 2550) $PN 1
J 0
(-590 2530);
DISPLAY 0.787234 (-590 2530);
PAINT MONO (-590 2530);
FORCEPROP 1 LASTPIN (-600 2350) $PN 2
J 0
(-590 2330);
DISPLAY 0.787234 (-590 2330);
PAINT MONO (-590 2330);
FORCEPROP 1 LAST VOLTAGE 4V
J 0
(-550 2450);
DISPLAY 0.638298 (-550 2450);
FORCEPROP 1 LAST VALUE 100UF
J 0
(-550 2500);
DISPLAY 0.638298 (-550 2500);
FORCEPROP 1 LAST PACK_TYPE C0805
J 0
(-550 2250);
DISPLAY 0.638298 (-550 2250);
FORCEPROP 1 LAST MATERIAL X6S
J 0
(-550 2350);
DISPLAY 0.638298 (-550 2350);
FORCEPROP 1 LAST TOLERANCE 20%
J 0
(-550 2400);
DISPLAY 0.638298 (-550 2400);
FORCEPROP 2 LAST CDS_LIB pure_quanta
J 0
(-600 2450);
DISPLAY INVISIBLE (-600 2450);
FORCEPROP 1 LAST PATH I96
J 0
(-550 2600);
DISPLAY 0.978723 (-550 2600);
PAINT WHITE (-550 2600);
DISPLAY INVISIBLE (-550 2600);
FORCEPROP 1 LAST PART_NUMBER CH710KMEA01
J 0
(-550 2300);
DISPLAY 0.638298 (-550 2300);
DISPLAY INVISIBLE (-550 2300);
FORCEADD DNS..2
(-4500 2925);
PAINT RED (-4500 2925);
FORCEPROP 2 LAST CDS_LIB mstr_misc
J 0
(-4500 2925);
DISPLAY INVISIBLE (-4500 2925);
FORCEPROP 1 LAST COMMENT_BODY TRUE
J 0
(-4500 2925);
DISPLAY INVISIBLE (-4500 2925);
FORCEADD CAD_NOTE..1
(-5250 2625);
FORCEPROP 0 LAST S1 R1094 AND R1095 COLAY
J 0
(-5375 2500);
DISPLAY 0.808511 (-5375 2500);
PAINT WHITE (-5375 2500);
FORCEPROP 2 LAST CDS_LIB pure_quanta_power
J 0
(-5250 2625);
DISPLAY INVISIBLE (-5250 2625);
FORCEPROP 1 LAST COMMENT_BODY TRUE
J 0
(-5225 2725);
DISPLAY 0.978723 (-5225 2725);
DISPLAY INVISIBLE (-5225 2725);
FORCEADD DNS..2
(-7825 3725);
PAINT RED (-7825 3725);
FORCEPROP 2 LAST CDS_LIB mstr_misc
J 0
(-7825 3725);
DISPLAY INVISIBLE (-7825 3725);
FORCEPROP 1 LAST COMMENT_BODY TRUE
J 0
(-7825 3725);
DISPLAY INVISIBLE (-7825 3725);
FORCEADD CAD_NOTE..1
(-8300 3125);
FORCEPROP 0 LAST S1 L30/R1093 COLAY WITH R1086/R1087
J 0
(-8425 3000);
DISPLAY 0.808511 (-8425 3000);
PAINT WHITE (-8425 3000);
FORCEPROP 2 LAST CDS_LIB pure_quanta_power
J 0
(-8300 3125);
DISPLAY INVISIBLE (-8300 3125);
FORCEPROP 1 LAST COMMENT_BODY TRUE
J 0
(-8275 3225);
DISPLAY 0.978723 (-8275 3225);
DISPLAY INVISIBLE (-8275 3225);
FORCEADD DNS..2
(-7825 3900);
PAINT RED (-7825 3900);
FORCEPROP 2 LAST CDS_LIB mstr_misc
J 0
(-7825 3900);
DISPLAY INVISIBLE (-7825 3900);
FORCEPROP 1 LAST COMMENT_BODY TRUE
J 0
(-7825 3900);
DISPLAY INVISIBLE (-7825 3900);
FORCEADD DNS..2
(-8150 4300);
PAINT RED (-8150 4300);
FORCEPROP 2 LAST CDS_LIB mstr_misc
J 0
(-8150 4300);
DISPLAY INVISIBLE (-8150 4300);
FORCEPROP 1 LAST COMMENT_BODY TRUE
J 0
(-8150 4300);
DISPLAY INVISIBLE (-8150 4300);
FORCEADD QUANTA_TITLE_BLOCK_C..1
(0 0);
FORCEPROP 0 LAST CDS_CON_LAST_MODIFIED Thu Sep 14 16:13:10 2023
J 0
(-1885 15);
DISPLAY INVISIBLE (-1885 15);
FORCEPROP 1 LAST CUSTOM_TXT_CDS <CON_LAST_MODIFIED>
J 0
(-1885 15);
DISPLAY 0.978723 (-1885 15);
FORCEPROP 2 LAST CUSTOM_TXT_CDS <XR_PAGE_TITLE>
J 0
(-7890 5250);
DISPLAY 0.638298 (-7890 5250);
PAINT PINK (-7890 5250);
DISPLAY INVISIBLE (-7890 5250);
FORCEPROP 1 LAST CUSTOM_TXT_CDS <NAME_2>
J 0
(-3175 50);
FORCEPROP 1 LAST CUSTOM_TXT_CDS <NAME_1>
J 0
(-3175 175);
FORCEPROP 1 LAST CUSTOM_TXT_CDS <Q_NUMBER>
J 0
(-1403 103);
DISPLAY 1.212766 (-1403 103);
FORCEPROP 1 LAST CUSTOM_TXT_CDS <Q_PROJ>
J 0
(-2382 102);
DISPLAY 1.212766 (-2382 102);
FORCEPROP 1 LAST CUSTOM_TXT_CDS <Q_REV>
J 0
(-184 103);
DISPLAY 1.212766 (-184 103);
FORCEPROP 1 LAST CUSTOM_TXT_CDS <CON_PAGE_NUM> OF <CON_TOTAL_PAGES>
J 0
(-446 18);
DISPLAY 0.978723 (-446 18);
FORCEPROP 1 LAST Q_TITLE RETIMER_CPU0_P3 DECAPS(8)
J 0
(-9366 26);
DISPLAY 2.446809 (-9366 26);
PAINT GREEN (-9366 26);
FORCEPROP 2 LAST CDS_LIB pure_quanta
J 0
(0 0);
DISPLAY INVISIBLE (0 0);
FORCEPROP 1 LAST CDS_LMAN_SYM_OUTLINE -9475,6775,100,-125
J 0
(0 0);
DISPLAY 0.468085 (0 0);
PAINT GREEN (0 0);
DISPLAY INVISIBLE (0 0);
FORCEPROP 2 LAST PAGE_BORDER TRUE
J 0
(-7890 5250);
DISPLAY 0.638298 (-7890 5250);
PAINT PINK (-7890 5250);
DISPLAY INVISIBLE (-7890 5250);
FORCEPROP 2 LAST CDS_XR_PAGE_TITLE CR-313 : @T6G_MB_LIB.T6G(SCH_1):PAGE313
J 0
(-7890 5250);
DISPLAY 0.638298 (-7890 5250);
PAINT PINK (-7890 5250);
DISPLAY INVISIBLE (-7890 5250);
FORCEPROP 1 LAST Q_DEPT BU9
J 1
(-3763 49);
DISPLAY 1.957447 (-3763 49);
PAINT GREEN (-3763 49);
DISPLAY INVISIBLE (-3763 49);
FORCEPROP 1 LAST COMMENT_BODY TRUE
J 0
(12 -13);
DISPLAY 0.978723 (12 -13);
PAINT GREEN (12 -13);
DISPLAY INVISIBLE (12 -13);
WIRE 16 -1 (-600 2675)(-900 2675);
WIRE 16 -1 (-600 2675)(-600 2550);
WIRE 16 -1 (-900 2550)(-900 2675);
WIRE 16 -1 (-900 2675)(-1200 2675);
WIRE 16 -1 (-1525 2675)(-1200 2675);
WIRE 16 -1 (-1200 2550)(-1200 2675);
WIRE 16 -1 (-1525 2525)(-1525 2675);
WIRE 16 -1 (-1525 2675)(-1775 2675);
WIRE 16 -1 (-1775 2525)(-1775 2675);
WIRE 16 -1 (-2050 2675)(-1775 2675);
WIRE 16 -1 (-2325 2675)(-2050 2675);
WIRE 16 -1 (-2050 2525)(-2050 2675);
WIRE 16 -1 (-2325 2525)(-2325 2675);
WIRE 16 -1 (-2575 2675)(-2325 2675);
WIRE 16 -1 (-2825 2675)(-2575 2675);
WIRE 16 -1 (-2575 2525)(-2575 2675);
WIRE 16 -1 (-3050 2675)(-2825 2675);
WIRE 16 -1 (-2825 2675)(-2825 2525);
WIRE 16 -1 (-3050 2675)(-3050 2525);
WIRE 16 -1 (-3350 2675)(-3050 2675);
WIRE 16 -1 (-3350 2675)(-3350 2525);
WIRE 16 -1 (-3800 2675)(-3350 2675);
WIRE 16 -1 (-3800 3350)(-3800 2675);
WIRE 16 -1 (-3800 2675)(-3975 2675);
WIRE 16 -1 (-3800 3975)(-3800 3350);
WIRE 16 -1 (-3800 3350)(-3625 3350);
WIRE 16 -1 (-3625 3350)(-3400 3350);
WIRE 16 -1 (-3625 3350)(-3625 3225);
WIRE 16 -1 (-3800 4625)(-3800 3975);
WIRE 16 -1 (-3800 3975)(-3625 3975);
WIRE 16 -1 (-3625 3975)(-3400 3975);
WIRE 16 -1 (-3625 3850)(-3625 3975);
WIRE 16 -1 (-3800 4625)(-3625 4625);
WIRE 16 -1 (-3875 4625)(-3800 4625);
WIRE 16 -1 (-3400 3350)(-3150 3350);
WIRE 16 -1 (-3400 3350)(-3400 3225);
WIRE 16 -1 (-3150 3350)(-2925 3350);
WIRE 16 -1 (-3150 3350)(-3150 3225);
WIRE 16 -1 (-3625 4625)(-3400 4625);
WIRE 16 -1 (-3625 4975)(-3625 4625);
WIRE 16 -1 (-3625 4625)(-3625 4475);
WIRE 16 -1 (-3400 3975)(-3175 3975);
WIRE 16 -1 (-3400 3850)(-3400 3975);
WIRE 16 -1 (-3175 3975)(-2950 3975);
WIRE 16 -1 (-3175 3850)(-3175 3975);
WIRE 16 -1 (-3175 4625)(-3400 4625);
WIRE 16 -1 (-3400 4625)(-3400 4475);
WIRE 16 -1 (-2925 3350)(-2675 3350);
WIRE 16 -1 (-2925 3350)(-2925 3225);
WIRE 16 -1 (-2675 3350)(-2450 3350);
WIRE 16 -1 (-2675 3350)(-2675 3225);
WIRE 16 -1 (-2950 4625)(-3175 4625);
WIRE 16 -1 (-3175 4625)(-3175 4475);
WIRE 16 -1 (-2950 3975)(-2700 3975);
WIRE 16 -1 (-2950 3850)(-2950 3975);
WIRE 16 -1 (-2700 3975)(-2475 3975);
WIRE 16 -1 (-2700 3850)(-2700 3975);
WIRE 16 -1 (-2700 4625)(-2950 4625);
WIRE 16 -1 (-2950 4625)(-2950 4475);
WIRE 16 -1 (-2450 3350)(-2225 3350);
WIRE 16 -1 (-2450 3350)(-2450 3200);
WIRE 16 -1 (-2000 3350)(-2225 3350);
WIRE 16 -1 (-2225 3200)(-2225 3350);
WIRE 16 -1 (-2475 4625)(-2700 4625);
WIRE 16 -1 (-2700 4625)(-2700 4475);
WIRE 16 -1 (-2475 3975)(-2250 3975);
WIRE 16 -1 (-2475 3850)(-2475 3975);
WIRE 16 -1 (-2250 3975)(-2025 3975);
WIRE 16 -1 (-2250 3850)(-2250 3975);
WIRE 16 -1 (-2250 4625)(-2475 4625);
WIRE 16 -1 (-2475 4625)(-2475 4475);
WIRE 16 -1 (-2000 3350)(-1750 3350);
WIRE 16 -1 (-2000 3200)(-2000 3350);
WIRE 16 -1 (-1750 3350)(-1750 3200);
WIRE 16 -1 (-2025 4625)(-2250 4625);
WIRE 16 -1 (-2250 4625)(-2250 4475);
WIRE 16 -1 (-2025 3975)(-1800 3975);
WIRE 16 -1 (-2025 3850)(-2025 3975);
WIRE 16 -1 (-1550 3975)(-1800 3975);
WIRE 16 -1 (-1800 3850)(-1800 3975);
WIRE 16 -1 (-1725 4625)(-2025 4625);
WIRE 16 -1 (-2025 4625)(-2025 4475);
WIRE 16 -1 (-1725 4625)(-1425 4625);
WIRE 16 -1 (-1725 4625)(-1725 4475);
WIRE 16 -1 (-1550 3975)(-1550 3850);
WIRE 16 -1 (-1425 4625)(-1425 4475);
WIRE 16 -1 (-3625 3025)(-3625 2800);
WIRE 16 -1 (-3625 2800)(-3400 2800);
WIRE 16 -1 (-3400 2800)(-3150 2800);
WIRE 16 -1 (-3400 3025)(-3400 2800);
WIRE 16 -1 (-3150 2800)(-2925 2800);
WIRE 16 -1 (-3150 3025)(-3150 2800);
WIRE 16 -1 (-2925 2800)(-2675 2800);
WIRE 16 -1 (-2925 3025)(-2925 2800);
WIRE 16 -1 (-2675 2800)(-2450 2800);
WIRE 16 -1 (-2675 3025)(-2675 2800);
WIRE 16 -1 (-2450 2800)(-2225 2800);
WIRE 16 -1 (-2450 3000)(-2450 2800);
WIRE 16 -1 (-2000 2800)(-2225 2800);
WIRE 16 -1 (-2225 3000)(-2225 2800);
WIRE 16 -1 (-2000 2800)(-1750 2800);
WIRE 16 -1 (-2000 3000)(-2000 2800);
WIRE 16 -1 (-1025 2800)(-1750 2800);
WIRE 16 -1 (-1750 3000)(-1750 2800);
WIRE 16 -1 (-1025 3525)(-1025 2800);
WIRE 16 -1 (-1025 2800)(-1025 2750);
WIRE 16 -1 (-1025 4125)(-1025 3525);
WIRE 16 -1 (-1025 3525)(-1550 3525);
WIRE 16 -1 (-1550 3650)(-1550 3525);
WIRE 16 -1 (-1550 3525)(-1800 3525);
WIRE 16 -1 (-1025 4125)(-1425 4125);
WIRE 16 -1 (-1425 4275)(-1425 4125);
WIRE 16 -1 (-1425 4125)(-1725 4125);
WIRE 16 -1 (-1800 3650)(-1800 3525);
WIRE 16 -1 (-2025 3525)(-1800 3525);
WIRE 16 -1 (-2025 3650)(-2025 3525);
WIRE 16 -1 (-2250 3525)(-2025 3525);
WIRE 16 -1 (-1725 4275)(-1725 4125);
WIRE 16 -1 (-1725 4125)(-2025 4125);
WIRE 16 -1 (-2025 4275)(-2025 4125);
WIRE 16 -1 (-2025 4125)(-2250 4125);
WIRE 16 -1 (-2250 3650)(-2250 3525);
WIRE 16 -1 (-2475 3525)(-2250 3525);
WIRE 16 -1 (-2475 3650)(-2475 3525);
WIRE 16 -1 (-2700 3525)(-2475 3525);
WIRE 16 -1 (-2250 4275)(-2250 4125);
WIRE 16 -1 (-2250 4125)(-2475 4125);
WIRE 16 -1 (-2475 4275)(-2475 4125);
WIRE 16 -1 (-2475 4125)(-2700 4125);
WIRE 16 -1 (-2700 3650)(-2700 3525);
WIRE 16 -1 (-2950 3525)(-2700 3525);
WIRE 16 -1 (-2950 3650)(-2950 3525);
WIRE 16 -1 (-3175 3525)(-2950 3525);
WIRE 16 -1 (-2700 4275)(-2700 4125);
WIRE 16 -1 (-2700 4125)(-2950 4125);
WIRE 16 -1 (-2950 4275)(-2950 4125);
WIRE 16 -1 (-3175 4125)(-2950 4125);
WIRE 16 -1 (-3175 3650)(-3175 3525);
WIRE 16 -1 (-3400 3525)(-3175 3525);
WIRE 16 -1 (-3400 3650)(-3400 3525);
WIRE 16 -1 (-3625 3525)(-3400 3525);
WIRE 16 -1 (-3175 4275)(-3175 4125);
WIRE 16 -1 (-3400 4125)(-3175 4125);
WIRE 16 -1 (-3400 4275)(-3400 4125);
WIRE 16 -1 (-3625 4125)(-3400 4125);
WIRE 16 -1 (-3625 3650)(-3625 3525);
WIRE 16 -1 (-3625 4275)(-3625 4125);
WIRE 16 -1 (-1275 5875)(-1275 5700);
WIRE 16 -1 (-1550 5875)(-1275 5875);
WIRE 16 -1 (-1550 5875)(-1550 5700);
WIRE 16 -1 (-1800 5875)(-1550 5875);
WIRE 16 -1 (-1800 5700)(-1800 5875);
WIRE 16 -1 (-2075 5875)(-1800 5875);
WIRE 16 -1 (-2075 5875)(-2075 5700);
WIRE 16 -1 (-2375 5875)(-2075 5875);
WIRE 16 -1 (-2375 5875)(-2375 5725);
WIRE 16 -1 (-2675 5875)(-2375 5875);
WIRE 16 -1 (-2675 5875)(-2675 5725);
WIRE 16 -1 (-2975 5875)(-2675 5875);
WIRE 16 -1 (-2975 5875)(-2975 5725);
WIRE 16 -1 (-3300 5875)(-2975 5875);
WIRE 16 -1 (-3300 5875)(-3300 5750);
WIRE 16 -1 (-3575 5875)(-3300 5875);
WIRE 16 -1 (-3575 5875)(-3575 5750);
WIRE 16 -1 (-4450 5875)(-3575 5875);
WIRE 16 -1 (-4450 6100)(-4450 5875);
WIRE 16 -1 (-4450 4625)(-4450 5875);
WIRE 16 -1 (-4075 4625)(-4450 4625);
WIRE 16 -1 (-4450 4625)(-4450 3050);
WIRE 16 -1 (-1275 5500)(-1275 5325);
WIRE 16 -1 (-1275 5325)(-1350 5325);
WIRE 16 -1 (-1350 5325)(-1550 5325);
WIRE 16 -1 (-1350 5325)(-1350 5250);
WIRE 16 -1 (-1550 5500)(-1550 5325);
WIRE 16 -1 (-1800 5325)(-1550 5325);
WIRE 16 -1 (-1800 5500)(-1800 5325);
WIRE 16 -1 (-2075 5325)(-1800 5325);
WIRE 16 -1 (-2075 5500)(-2075 5325);
WIRE 16 -1 (-2075 5325)(-2375 5325);
WIRE 16 -1 (-2375 5525)(-2375 5325);
WIRE 16 -1 (-2675 5325)(-2375 5325);
WIRE 16 -1 (-2675 5525)(-2675 5325);
WIRE 16 -1 (-2975 5325)(-2675 5325);
WIRE 16 -1 (-2975 5525)(-2975 5325);
WIRE 16 -1 (-3300 5325)(-2975 5325);
WIRE 16 -1 (-3300 5550)(-3300 5325);
WIRE 16 -1 (-3575 5325)(-3300 5325);
WIRE 16 -1 (-3575 5550)(-3575 5325);
WIRE 16 -1 (-8250 4475)(-8250 4375);
WIRE 16 -1 (-8300 4475)(-8250 4475);
WIRE 16 -1 (-8300 4625)(-8300 4475);
WIRE 16 -1 (-8300 4475)(-8350 4475);
WIRE 16 -1 (-8350 4475)(-8350 4400);
WIRE 16 -1 (-8300 4625)(-8025 4625);
WIRE 16 -1 (-8300 5350)(-8300 4625);
WIRE 16 -1 (-7200 5350)(-8300 5350);
WIRE 16 -1 (-8300 5425)(-8300 5350);
WIRE 16 -1 (-7200 5350)(-6950 5350);
WIRE 16 -1 (-7200 5350)(-7200 5300);
WIRE 16 -1 (-6950 5350)(-6700 5350);
WIRE 16 -1 (-6950 5350)(-6950 5300);
WIRE 16 -1 (-6700 5350)(-6450 5350);
WIRE 16 -1 (-6700 5350)(-6700 5275);
WIRE 16 -1 (-6450 5350)(-6450 5275);
WIRE 16 -1 (-6450 5075)(-6450 4950);
WIRE 16 -1 (-6525 4950)(-6450 4950);
WIRE 16 -1 (-6700 4950)(-6525 4950);
WIRE 16 -1 (-6700 5075)(-6700 4950);
WIRE 16 -1 (-6950 4950)(-6700 4950);
WIRE 16 -1 (-6950 5100)(-6950 4950);
WIRE 16 -1 (-7200 4950)(-6950 4950);
WIRE 16 -1 (-7200 5100)(-7200 4950);
WIRE 16 -1 (-5300 4625)(-5575 4625);
WIRE 16 -1 (-5300 4625)(-5300 4475);
WIRE 16 -1 (-5575 4625)(-5575 4475);
WIRE 16 -1 (-5575 4625)(-5825 4625);
WIRE 16 -1 (-5825 4625)(-6075 4625);
WIRE 16 -1 (-5825 4625)(-5825 4475);
WIRE 16 -1 (-6075 4625)(-6075 4475);
WIRE 16 -1 (-6300 4625)(-6075 4625);
WIRE 16 -1 (-6300 4625)(-6500 4625);
WIRE 16 -1 (-6300 4625)(-6300 4475);
WIRE 16 -1 (-6500 4625)(-6500 4475);
WIRE 16 -1 (-6500 4625)(-6725 4625);
WIRE 16 -1 (-6925 4625)(-6725 4625);
WIRE 16 -1 (-6725 4625)(-6725 4475);
WIRE 16 -1 (-6925 4625)(-7125 4625);
WIRE 16 -1 (-6925 4625)(-6925 4475);
WIRE 16 -1 (-7125 4625)(-7125 4475);
WIRE 16 -1 (-7350 4625)(-7125 4625);
WIRE 16 -1 (-7350 4625)(-7450 4625);
WIRE 16 -1 (-7350 4625)(-7350 4475);
WIRE 16 -1 (-7450 4800)(-7450 4625);
WIRE 16 -1 (-7450 4625)(-7825 4625);
WIRE 16 -1 (-7450 3850)(-7450 4625);
WIRE 16 -1 (-7550 3850)(-7450 3850);
WIRE 16 -1 (-7550 3850)(-7550 3750);
WIRE 16 -1 (-7550 3950)(-7550 3850);
WIRE 16 -1 (-7750 3950)(-7550 3950);
WIRE 16 -1 (-7750 3750)(-7550 3750);
WIRE 16 -1 (-5300 4275)(-5300 4175);
WIRE 16 -1 (-5575 4175)(-5300 4175);
WIRE 16 -1 (-5575 4275)(-5575 4175);
WIRE 16 -1 (-5825 4175)(-5575 4175);
WIRE 16 -1 (-5825 4275)(-5825 4175);
WIRE 16 -1 (-6075 4175)(-5825 4175);
WIRE 16 -1 (-6075 4275)(-6075 4175);
WIRE 16 -1 (-6300 4175)(-6075 4175);
WIRE 16 -1 (-6500 4175)(-6300 4175);
WIRE 16 -1 (-6300 4175)(-6300 4100);
WIRE 16 -1 (-6300 4275)(-6300 4175);
WIRE 16 -1 (-6500 4275)(-6500 4175);
WIRE 16 -1 (-6725 4175)(-6500 4175);
WIRE 16 -1 (-6725 4275)(-6725 4175);
WIRE 16 -1 (-6925 4175)(-6725 4175);
WIRE 16 -1 (-6925 4275)(-6925 4175);
WIRE 16 -1 (-7125 4175)(-6925 4175);
WIRE 16 -1 (-7125 4275)(-7125 4175);
WIRE 16 -1 (-7350 4175)(-7125 4175);
WIRE 16 -1 (-7350 4275)(-7350 4175);
WIRE 16 -1 (-3350 2325)(-3350 2200);
WIRE 16 -1 (-3350 2200)(-3050 2200);
WIRE 16 -1 (-3050 2325)(-3050 2200);
WIRE 16 -1 (-3050 2200)(-2825 2200);
WIRE 16 -1 (-2825 2200)(-2575 2200);
WIRE 16 -1 (-2825 2325)(-2825 2200);
WIRE 16 -1 (-2575 2200)(-2325 2200);
WIRE 16 -1 (-2575 2325)(-2575 2200);
WIRE 16 -1 (-2325 2200)(-2050 2200);
WIRE 16 -1 (-2325 2325)(-2325 2200);
WIRE 16 -1 (-1775 2200)(-2050 2200);
WIRE 16 -1 (-2050 2325)(-2050 2200);
WIRE 16 -1 (-1775 2200)(-1525 2200);
WIRE 16 -1 (-1775 2325)(-1775 2200);
WIRE 16 -1 (-1200 2200)(-1525 2200);
WIRE 16 -1 (-1525 2325)(-1525 2200);
WIRE 16 -1 (-1525 2200)(-1525 2050);
WIRE 16 -1 (-900 2200)(-1200 2200);
WIRE 16 -1 (-1200 2350)(-1200 2200);
WIRE 16 -1 (-600 2200)(-900 2200);
WIRE 16 -1 (-900 2350)(-900 2200);
WIRE 16 -1 (-600 2350)(-600 2200);
WIRE 16 -1 (-6925 3200)(-6925 3025);
WIRE 16 -1 (-6925 3025)(-6650 3025);
WIRE 16 -1 (-6650 3175)(-6650 3025);
WIRE 16 -1 (-6650 3025)(-6650 2925);
WIRE 16 -1 (-2375 1425)(-2375 1575);
WIRE 16 -1 (-2375 1575)(-2625 1575);
WIRE 16 -1 (-2625 1575)(-2925 1575);
WIRE 16 -1 (-2625 1425)(-2625 1575);
WIRE 16 -1 (-2925 1575)(-2925 1425);
WIRE 16 -1 (-2925 1575)(-3175 1575);
WIRE 16 -1 (-3175 1575)(-3300 1575);
WIRE 16 -1 (-3175 1575)(-3175 1425);
WIRE 16 -1 (-3300 1800)(-3300 1575);
WIRE 16 -1 (-4450 1575)(-3300 1575);
WIRE 16 -1 (-4450 1575)(-4450 2675);
WIRE 16 -1 (-4450 2675)(-4175 2675);
WIRE 16 -1 (-4450 2850)(-4450 2675);
WIRE 16 -1 (-3175 1225)(-3175 1100);
WIRE 16 -1 (-3175 1100)(-2925 1100);
WIRE 16 -1 (-2925 1100)(-2625 1100);
WIRE 16 -1 (-2925 1225)(-2925 1100);
WIRE 16 -1 (-2625 1100)(-2475 1100);
WIRE 16 -1 (-2625 1225)(-2625 1100);
WIRE 16 -1 (-2375 1100)(-2475 1100);
WIRE 16 -1 (-2475 1100)(-2475 1050);
WIRE 16 -1 (-2375 1225)(-2375 1100);
WIRE 16 -1 (-7950 3950)(-8200 3950);
WIRE 16 -1 (-8200 3950)(-8200 3850);
WIRE 16 -1 (-8300 3850)(-8200 3850);
WIRE 16 -1 (-8200 3850)(-8200 3750);
WIRE 16 -1 (-8200 3750)(-7950 3750);
WIRE 16 -1 (-8300 3850)(-8300 4025);
WIRE 16 -1 (-8300 3525)(-8300 3850);
WIRE 16 -1 (-8300 3525)(-7050 3525);
WIRE 16 -1 (-8300 4025)(-8250 4025);
WIRE 16 -1 (-8350 4025)(-8300 4025);
WIRE 16 -1 (-8350 4025)(-8350 4200);
WIRE 16 -1 (-8250 4025)(-8250 4175);
WIRE 16 -1 (-6925 3525)(-7050 3525);
WIRE 16 -1 (-7050 3525)(-7050 3625);
WIRE 16 -1 (-6925 3525)(-6650 3525);
WIRE 16 -1 (-6925 3400)(-6925 3525);
WIRE 16 -1 (-6650 3525)(-6650 3375);
DOT 1 (-2625 1100);
DOT 1 (-2625 1575);
DOT 1 (-2925 1100);
DOT 1 (-2925 1575);
DOT 1 (-2575 2200);
DOT 1 (-2000 2800);
DOT 1 (-2000 3350);
DOT 1 (-1750 2800);
DOT 1 (-2475 3525);
DOT 1 (-1025 2800);
DOT 1 (-2675 2800);
DOT 1 (-2450 2800);
DOT 1 (-2225 2800);
DOT 1 (-2475 1100);
DOT 1 (-2250 3525);
DOT 1 (-2225 3350);
DOT 1 (-1025 3525);
DOT 1 (-3350 2675);
DOT 1 (-2925 2800);
DOT 1 (-2475 4125);
DOT 1 (-2675 3350);
DOT 1 (-3150 3350);
DOT 1 (-3400 3350);
DOT 1 (-3400 3525);
DOT 1 (-2050 2675);
DOT 1 (-2025 4125);
DOT 1 (-2825 2675);
DOT 1 (-2700 3525);
DOT 1 (-2950 3525);
DOT 1 (-2450 3350);
DOT 1 (-2575 2675);
DOT 1 (-2475 3975);
DOT 1 (-2025 4625);
DOT 1 (-3175 3975);
DOT 1 (-6300 4175);
DOT 1 (-5825 4625);
DOT 1 (-2050 2200);
DOT 1 (-1800 3975);
DOT 1 (-1425 4125);
DOT 1 (-2250 3975);
DOT 1 (-1725 4125);
DOT 1 (-2475 4625);
DOT 1 (-3175 4625);
DOT 1 (-2375 5325);
DOT 1 (-2075 5875);
DOT 1 (-1550 5875);
DOT 1 (-2075 5325);
DOT 1 (-1800 5875);
DOT 1 (-2975 5875);
DOT 1 (-7200 5350);
DOT 1 (-6950 4950);
DOT 1 (-6500 4175);
DOT 1 (-6300 4625);
DOT 1 (-5575 4175);
DOT 1 (-7550 3850);
DOT 1 (-6925 3525);
DOT 1 (-6700 4950);
DOT 1 (-6500 4625);
DOT 1 (-7350 4625);
DOT 1 (-6725 4625);
DOT 1 (-6925 4625);
DOT 1 (-7450 4625);
DOT 1 (-7125 4625);
DOT 1 (-6700 5350);
DOT 1 (-6950 5350);
DOT 1 (-8300 5350);
DOT 1 (-6725 4175);
DOT 1 (-6650 3025);
DOT 1 (-8300 4025);
DOT 1 (-6925 4175);
DOT 1 (-3400 4625);
DOT 1 (-2325 2675);
DOT 1 (-3800 2675);
DOT 1 (-8300 3850);
DOT 1 (-7050 3525);
DOT 1 (-4450 2675);
DOT 1 (-8300 4625);
DOT 1 (-7125 4175);
DOT 1 (-6075 4175);
DOT 1 (-6075 4625);
DOT 1 (-5825 4175);
DOT 1 (-5575 4625);
DOT 1 (-4450 4625);
DOT 1 (-4450 5875);
DOT 1 (-3300 1575);
DOT 1 (-3175 1575);
DOT 1 (-3400 2800);
DOT 1 (-3800 3350);
DOT 1 (-3625 3350);
DOT 1 (-3800 3975);
DOT 1 (-3625 3975);
DOT 1 (-3400 3975);
DOT 1 (-3050 2200);
DOT 1 (-3150 2800);
DOT 1 (-3050 2675);
DOT 1 (-2825 2200);
DOT 1 (-2925 3350);
DOT 1 (-3175 3525);
DOT 1 (-2700 3975);
DOT 1 (-2325 2200);
DOT 1 (-1775 2200);
DOT 1 (-1800 3525);
DOT 1 (-1550 3525);
DOT 1 (-3400 4125);
DOT 1 (-3800 4625);
DOT 1 (-3575 5875);
DOT 1 (-2950 4125);
DOT 1 (-2700 4125);
DOT 1 (-3300 5325);
DOT 1 (-2975 5325);
DOT 1 (-3300 5875);
DOT 1 (-2675 5325);
DOT 1 (-2675 5875);
DOT 1 (-2375 5875);
DOT 1 (-2250 4625);
DOT 1 (-1725 4625);
DOT 1 (-1800 5325);
DOT 1 (-1550 5325);
DOT 1 (-1350 5325);
DOT 1 (-8300 4475);
DOT 1 (-8200 3850);
DOT 1 (-3625 4625);
DOT 1 (-2950 4625);
DOT 1 (-2250 4125);
DOT 1 (-2025 3975);
DOT 1 (-1525 2200);
DOT 1 (-900 2675);
DOT 1 (-900 2200);
DOT 1 (-1200 2200);
DOT 1 (-1200 2675);
DOT 1 (-2025 3525);
DOT 1 (-1775 2675);
DOT 1 (-1525 2675);
DOT 1 (-3175 4125);
DOT 1 (-2950 3975);
DOT 1 (-2700 4625);
QUIT
